FILE_TYPE = MACRO_DRAWING;
SET COLOR_WIRE YELLOW;
SET COLOR_PROP MONO;
SET COLOR_DOT WHITE;
SET COLOR_ARC YELLOW;
SET COLOR_BODY GREEN;
SET COLOR_NOTE MONO;
SET PROP_DISPLAY VALUE;
SET PAGE_NUMBER P56;
FORCEADD OFFPAGE..4
(-1550 2850);
FORCEPROP 2 LAST $XR3 22 
J 0
(-1004 2850);
DISPLAY 0.638298 (-1004 2850);
PAINT MONO (-1004 2850);
FORCEPROP 2 LAST $XR2 254 
J 0
(-1124 2850);
DISPLAY 0.638298 (-1124 2850);
PAINT MONO (-1124 2850);
FORCEPROP 2 LAST $XR1 118 
J 0
(-1244 2850);
DISPLAY 0.638298 (-1244 2850);
PAINT MONO (-1244 2850);
FORCEPROP 2 LAST $XR0 111 
J 0
(-1364 2850);
DISPLAY 0.638298 (-1364 2850);
PAINT MONO (-1364 2850);
FORCEPROP 2 LAST PATH I161
J 0
(-1225 2900);
DISPLAY 1.021277 (-1225 2900);
PAINT ORANGE (-1225 2900);
DISPLAY INVISIBLE (-1225 2900);
FORCEPROP 1 LAST COMMENT_BODY TRUE
J 0
(-1575 2750);
DISPLAY 0.680851 (-1575 2750);
PAINT PEACH (-1575 2750);
DISPLAY INVISIBLE (-1575 2750);
FORCEPROP 1 LAST OFFPAGE TRUE
J 0
(-1225 2725);
DISPLAY 0.680851 (-1225 2725);
PAINT GREEN (-1225 2725);
DISPLAY INVISIBLE (-1225 2725);
FORCEPROP 2 LAST CDS_LIB mstr_standard
J 0
(-1550 2850);
DISPLAY 0.787234 (-1550 2850);
PAINT MONO (-1550 2850);
DISPLAY INVISIBLE (-1550 2850);
FORCEADD OFFPAGE..4
(-1550 2450);
FORCEPROP 2 LAST $XR2 22 
J 0
(-1124 2450);
DISPLAY 0.638298 (-1124 2450);
PAINT MONO (-1124 2450);
FORCEPROP 2 LAST $XR1 255 
J 0
(-1244 2450);
DISPLAY 0.638298 (-1244 2450);
PAINT MONO (-1244 2450);
FORCEPROP 2 LAST $XR0 111 
J 0
(-1364 2450);
DISPLAY 0.638298 (-1364 2450);
PAINT MONO (-1364 2450);
FORCEPROP 2 LAST PATH I164
J 0
(-1225 2500);
DISPLAY 1.021277 (-1225 2500);
PAINT ORANGE (-1225 2500);
DISPLAY INVISIBLE (-1225 2500);
FORCEPROP 1 LAST COMMENT_BODY TRUE
J 0
(-1575 2350);
DISPLAY 0.680851 (-1575 2350);
PAINT PEACH (-1575 2350);
DISPLAY INVISIBLE (-1575 2350);
FORCEPROP 1 LAST OFFPAGE TRUE
J 0
(-1225 2325);
DISPLAY 0.680851 (-1225 2325);
PAINT GREEN (-1225 2325);
DISPLAY INVISIBLE (-1225 2325);
FORCEPROP 2 LAST CDS_LIB mstr_standard
J 0
(-1550 2450);
DISPLAY 0.787234 (-1550 2450);
PAINT MONO (-1550 2450);
DISPLAY INVISIBLE (-1550 2450);
FORCEADD SKX_EXT_B..2
(-4025 2550);
FORCEPROP 2 LASTPIN (-5275 2700) $PN G2
J 2
(-5285 2710);
DISPLAY 0.617021 (-5285 2710);
PAINT ORANGE (-5285 2710);
FORCEPROP 2 LASTPIN (-2775 1150) $PN AN24
J 0
(-2765 1160);
DISPLAY 0.617021 (-2765 1160);
PAINT ORANGE (-2765 1160);
FORCEPROP 2 LASTPIN (-2775 1100) $PN AN26
J 0
(-2765 1110);
DISPLAY 0.617021 (-2765 1110);
PAINT ORANGE (-2765 1110);
FORCEPROP 2 LASTPIN (-2775 2600) $PN AK57
J 0
(-2765 2610);
DISPLAY 0.617021 (-2765 2610);
PAINT ORANGE (-2765 2610);
FORCEPROP 1 LAST LOCATION U2D1
J 0
(-5225 4600);
DISPLAY 0.617021 (-5225 4600);
PAINT AQUA (-5225 4600);
FORCEPROP 1 LAST PART_NUMBER TBD
J 0
(-5225 550);
DISPLAY 0.617021 (-5225 550);
PAINT BLUE (-5225 550);
FORCEPROP 1 LAST MATERIAL IC
J 0
(-5225 4550);
DISPLAY 0.617021 (-5225 4550);
PAINT SKYBLUE (-5225 4550);
FORCEPROP 2 LASTPIN (-5275 1600) $PN AY13
J 2
(-5285 1610);
DISPLAY 0.617021 (-5285 1610);
PAINT ORANGE (-5285 1610);
FORCEPROP 2 LASTPIN (-2775 2350) $PN AN14
J 0
(-2765 2360);
DISPLAY 0.617021 (-2765 2360);
PAINT ORANGE (-2765 2360);
FORCEPROP 2 LASTPIN (-2775 2950) $PN AN12
J 0
(-2765 2960);
DISPLAY 0.617021 (-2765 2960);
PAINT ORANGE (-2765 2960);
FORCEPROP 2 LASTPIN (-2775 3000) $PN AM13
J 0
(-2765 3010);
DISPLAY 0.617021 (-2765 3010);
PAINT ORANGE (-2765 3010);
FORCEPROP 2 LASTPIN (-2775 3050) $PN AG46
J 0
(-2765 3060);
DISPLAY 0.617021 (-2765 3060);
PAINT ORANGE (-2765 3060);
FORCEPROP 2 LASTPIN (-2775 3100) $PN AF45
J 0
(-2765 3110);
DISPLAY 0.617021 (-2765 3110);
PAINT ORANGE (-2765 3110);
FORCEPROP 2 LASTPIN (-5275 4350) $PN A4
J 2
(-5285 4360);
DISPLAY 0.617021 (-5285 4360);
PAINT ORANGE (-5285 4360);
FORCEPROP 2 LASTPIN (-5275 4300) $PN A6
J 2
(-5285 4310);
DISPLAY 0.617021 (-5285 4310);
PAINT ORANGE (-5285 4310);
FORCEPROP 2 LASTPIN (-5275 4250) $PN A14
J 2
(-5285 4260);
DISPLAY 0.617021 (-5285 4260);
PAINT ORANGE (-5285 4260);
FORCEPROP 2 LASTPIN (-5275 4200) $PN A16
J 2
(-5285 4210);
DISPLAY 0.617021 (-5285 4210);
PAINT ORANGE (-5285 4210);
FORCEPROP 2 LASTPIN (-5275 4150) $PN A24
J 2
(-5285 4160);
DISPLAY 0.617021 (-5285 4160);
PAINT ORANGE (-5285 4160);
FORCEPROP 2 LASTPIN (-5275 4050) $PN B7
J 2
(-5285 4060);
DISPLAY 0.617021 (-5285 4060);
PAINT ORANGE (-5285 4060);
FORCEPROP 2 LASTPIN (-5275 3950) $PN B13
J 2
(-5285 3960);
DISPLAY 0.617021 (-5285 3960);
PAINT ORANGE (-5285 3960);
FORCEPROP 2 LASTPIN (-5275 3900) $PN B15
J 2
(-5285 3910);
DISPLAY 0.617021 (-5285 3910);
PAINT ORANGE (-5285 3910);
FORCEPROP 2 LASTPIN (-5275 3850) $PN B17
J 2
(-5285 3860);
DISPLAY 0.617021 (-5285 3860);
PAINT ORANGE (-5285 3860);
FORCEPROP 2 LASTPIN (-5275 3800) $PN B77
J 2
(-5285 3810);
DISPLAY 0.617021 (-5285 3810);
PAINT ORANGE (-5285 3810);
FORCEPROP 2 LASTPIN (-5275 3750) $PN B81
J 2
(-5285 3760);
DISPLAY 0.617021 (-5285 3760);
PAINT ORANGE (-5285 3760);
FORCEPROP 2 LASTPIN (-5275 3700) $PN C6
J 2
(-5285 3710);
DISPLAY 0.617021 (-5285 3710);
PAINT ORANGE (-5285 3710);
FORCEPROP 2 LASTPIN (-5275 3650) $PN C18
J 2
(-5285 3660);
DISPLAY 0.617021 (-5285 3660);
PAINT ORANGE (-5285 3660);
FORCEPROP 2 LASTPIN (-5275 3500) $PN C82
J 2
(-5285 3510);
DISPLAY 0.617021 (-5285 3510);
PAINT ORANGE (-5285 3510);
FORCEPROP 2 LASTPIN (-5275 3450) $PN D5
J 2
(-5285 3460);
DISPLAY 0.617021 (-5285 3460);
PAINT ORANGE (-5285 3460);
FORCEPROP 2 LASTPIN (-5275 3400) $PN D17
J 2
(-5285 3410);
DISPLAY 0.617021 (-5285 3410);
PAINT ORANGE (-5285 3410);
FORCEPROP 2 LASTPIN (-5275 3350) $PN D65
J 2
(-5285 3360);
DISPLAY 0.617021 (-5285 3360);
PAINT ORANGE (-5285 3360);
FORCEPROP 2 LASTPIN (-5275 3300) $PN D83
J 2
(-5285 3310);
DISPLAY 0.617021 (-5285 3310);
PAINT ORANGE (-5285 3310);
FORCEPROP 2 LASTPIN (-5275 3250) $PN E2
J 2
(-5285 3260);
DISPLAY 0.617021 (-5285 3260);
PAINT ORANGE (-5285 3260);
FORCEPROP 2 LASTPIN (-5275 3200) $PN E4
J 2
(-5285 3210);
DISPLAY 0.617021 (-5285 3210);
PAINT ORANGE (-5285 3210);
FORCEPROP 2 LASTPIN (-5275 3100) $PN E24
J 2
(-5285 3110);
DISPLAY 0.617021 (-5285 3110);
PAINT ORANGE (-5285 3110);
FORCEPROP 2 LASTPIN (-5275 3050) $PN E84
J 2
(-5285 3060);
DISPLAY 0.617021 (-5285 3060);
PAINT ORANGE (-5285 3060);
FORCEPROP 2 LASTPIN (-5275 3000) $PN F3
J 2
(-5285 3010);
DISPLAY 0.617021 (-5285 3010);
PAINT ORANGE (-5285 3010);
FORCEPROP 2 LASTPIN (-5275 2950) $PN F23
J 2
(-5285 2960);
DISPLAY 0.617021 (-5285 2960);
PAINT ORANGE (-5285 2960);
FORCEPROP 2 LASTPIN (-5275 2850) $PN F65
J 2
(-5285 2860);
DISPLAY 0.617021 (-5285 2860);
PAINT ORANGE (-5285 2860);
FORCEPROP 2 LASTPIN (-5275 2800) $PN F83
J 2
(-5285 2810);
DISPLAY 0.617021 (-5285 2810);
PAINT ORANGE (-5285 2810);
FORCEPROP 2 LASTPIN (-5275 2650) $PN G64
J 2
(-5285 2660);
DISPLAY 0.617021 (-5285 2660);
PAINT ORANGE (-5285 2660);
FORCEPROP 2 LASTPIN (-5275 2600) $PN G84
J 2
(-5285 2610);
DISPLAY 0.617021 (-5285 2610);
PAINT ORANGE (-5285 2610);
FORCEPROP 2 LASTPIN (-5275 2550) $PN H1
J 2
(-5285 2560);
DISPLAY 0.617021 (-5285 2560);
PAINT ORANGE (-5285 2560);
FORCEPROP 2 LASTPIN (-5275 2500) $PN H83
J 2
(-5285 2510);
DISPLAY 0.617021 (-5285 2510);
PAINT ORANGE (-5285 2510);
FORCEPROP 2 LASTPIN (-5275 2450) $PN H85
J 2
(-5285 2460);
DISPLAY 0.617021 (-5285 2460);
PAINT ORANGE (-5285 2460);
FORCEPROP 2 LASTPIN (-5275 2400) $PN J46
J 2
(-5285 2410);
DISPLAY 0.617021 (-5285 2410);
PAINT ORANGE (-5285 2410);
FORCEPROP 2 LASTPIN (-5275 2350) $PN J62
J 2
(-5285 2360);
DISPLAY 0.617021 (-5285 2360);
PAINT ORANGE (-5285 2360);
FORCEPROP 2 LASTPIN (-5275 2300) $PN K61
J 2
(-5285 2310);
DISPLAY 0.617021 (-5285 2310);
PAINT ORANGE (-5285 2310);
FORCEPROP 2 LASTPIN (-5275 2250) $PN M63
J 2
(-5285 2260);
DISPLAY 0.617021 (-5285 2260);
PAINT ORANGE (-5285 2260);
FORCEPROP 2 LASTPIN (-5275 2200) $PN P65
J 2
(-5285 2210);
DISPLAY 0.617021 (-5285 2210);
PAINT ORANGE (-5285 2210);
FORCEPROP 2 LASTPIN (-5275 2150) $PN R62
J 2
(-5285 2160);
DISPLAY 0.617021 (-5285 2160);
PAINT ORANGE (-5285 2160);
FORCEPROP 2 LASTPIN (-5275 2100) $PN R66
J 2
(-5285 2110);
DISPLAY 0.617021 (-5285 2110);
PAINT ORANGE (-5285 2110);
FORCEPROP 2 LASTPIN (-5275 2050) $PN T67
J 2
(-5285 2060);
DISPLAY 0.617021 (-5285 2060);
PAINT ORANGE (-5285 2060);
FORCEPROP 2 LASTPIN (-5275 2000) $PN U66
J 2
(-5285 2010);
DISPLAY 0.617021 (-5285 2010);
PAINT ORANGE (-5285 2010);
FORCEPROP 2 LASTPIN (-5275 1950) $PN V65
J 2
(-5285 1960);
DISPLAY 0.617021 (-5285 1960);
PAINT ORANGE (-5285 1960);
FORCEPROP 2 LASTPIN (-5275 1850) $PN V67
J 2
(-5285 1860);
DISPLAY 0.617021 (-5285 1860);
PAINT ORANGE (-5285 1860);
FORCEPROP 2 LASTPIN (-5275 1800) $PN W66
J 2
(-5285 1810);
DISPLAY 0.617021 (-5285 1810);
PAINT ORANGE (-5285 1810);
FORCEPROP 2 LASTPIN (-5275 1750) $PN Y23
J 2
(-5285 1760);
DISPLAY 0.617021 (-5285 1760);
PAINT ORANGE (-5285 1760);
FORCEPROP 2 LASTPIN (-5275 1700) $PN Y65
J 2
(-5285 1710);
DISPLAY 0.617021 (-5285 1710);
PAINT ORANGE (-5285 1710);
FORCEPROP 2 LASTPIN (-5275 1500) $PN AD47
J 2
(-5285 1510);
DISPLAY 0.617021 (-5285 1510);
PAINT ORANGE (-5285 1510);
FORCEPROP 2 LASTPIN (-5275 1450) $PN AD49
J 2
(-5285 1460);
DISPLAY 0.617021 (-5285 1460);
PAINT ORANGE (-5285 1460);
FORCEPROP 2 LASTPIN (-5275 1400) $PN AD51
J 2
(-5285 1410);
DISPLAY 0.617021 (-5285 1410);
PAINT ORANGE (-5285 1410);
FORCEPROP 2 LASTPIN (-5275 1350) $PN AE46
J 2
(-5285 1360);
DISPLAY 0.617021 (-5285 1360);
PAINT ORANGE (-5285 1360);
FORCEPROP 2 LASTPIN (-5275 1300) $PN AE48
J 2
(-5285 1310);
DISPLAY 0.617021 (-5285 1310);
PAINT ORANGE (-5285 1310);
FORCEPROP 2 LASTPIN (-5275 1250) $PN AE50
J 2
(-5285 1260);
DISPLAY 0.617021 (-5285 1260);
PAINT ORANGE (-5285 1260);
FORCEPROP 2 LASTPIN (-5275 1150) $PN AE52
J 2
(-5285 1160);
DISPLAY 0.617021 (-5285 1160);
PAINT ORANGE (-5285 1160);
FORCEPROP 2 LASTPIN (-5275 1100) $PN AE72
J 2
(-5285 1110);
DISPLAY 0.617021 (-5285 1110);
PAINT ORANGE (-5285 1110);
FORCEPROP 2 LASTPIN (-5275 1050) $PN AF19
J 2
(-5285 1060);
DISPLAY 0.617021 (-5285 1060);
PAINT ORANGE (-5285 1060);
FORCEPROP 2 LASTPIN (-5275 1000) $PN AF47
J 2
(-5285 1010);
DISPLAY 0.617021 (-5285 1010);
PAINT ORANGE (-5285 1010);
FORCEPROP 2 LASTPIN (-5275 950) $PN AF49
J 2
(-5285 960);
DISPLAY 0.617021 (-5285 960);
PAINT ORANGE (-5285 960);
FORCEPROP 2 LASTPIN (-5275 900) $PN AF51
J 2
(-5285 910);
DISPLAY 0.617021 (-5285 910);
PAINT ORANGE (-5285 910);
FORCEPROP 2 LASTPIN (-5275 750) $PN AF53
J 2
(-5285 760);
DISPLAY 0.617021 (-5285 760);
PAINT ORANGE (-5285 760);
FORCEPROP 2 LASTPIN (-2775 4350) $PN AF71
J 0
(-2765 4360);
DISPLAY 0.617021 (-2765 4360);
PAINT ORANGE (-2765 4360);
FORCEPROP 2 LASTPIN (-2775 4300) $PN AG20
J 0
(-2765 4310);
DISPLAY 0.617021 (-2765 4310);
PAINT ORANGE (-2765 4310);
FORCEPROP 2 LASTPIN (-2775 4250) $PN AG48
J 0
(-2765 4260);
DISPLAY 0.617021 (-2765 4260);
PAINT ORANGE (-2765 4260);
FORCEPROP 2 LASTPIN (-2775 4200) $PN AG50
J 0
(-2765 4210);
DISPLAY 0.617021 (-2765 4210);
PAINT ORANGE (-2765 4210);
FORCEPROP 2 LASTPIN (-2775 4150) $PN AG52
J 0
(-2765 4160);
DISPLAY 0.617021 (-2765 4160);
PAINT ORANGE (-2765 4160);
FORCEPROP 2 LASTPIN (-2775 4100) $PN AG54
J 0
(-2765 4110);
DISPLAY 0.617021 (-2765 4110);
PAINT ORANGE (-2765 4110);
FORCEPROP 2 LASTPIN (-2775 4050) $PN AG56
J 0
(-2765 4060);
DISPLAY 0.617021 (-2765 4060);
PAINT ORANGE (-2765 4060);
FORCEPROP 2 LASTPIN (-2775 3950) $PN AG72
J 0
(-2765 3960);
DISPLAY 0.617021 (-2765 3960);
PAINT ORANGE (-2765 3960);
FORCEPROP 2 LASTPIN (-2775 3900) $PN AH15
J 0
(-2765 3910);
DISPLAY 0.617021 (-2765 3910);
PAINT ORANGE (-2765 3910);
FORCEPROP 2 LASTPIN (-2775 3850) $PN AH19
J 0
(-2765 3860);
DISPLAY 0.617021 (-2765 3860);
PAINT ORANGE (-2765 3860);
FORCEPROP 2 LASTPIN (-2775 3800) $PN AH55
J 0
(-2765 3810);
DISPLAY 0.617021 (-2765 3810);
PAINT ORANGE (-2765 3810);
FORCEPROP 2 LASTPIN (-2775 3750) $PN AH57
J 0
(-2765 3760);
DISPLAY 0.617021 (-2765 3760);
PAINT ORANGE (-2765 3760);
FORCEPROP 2 LASTPIN (-2775 3700) $PN AH71
J 0
(-2765 3710);
DISPLAY 0.617021 (-2765 3710);
PAINT ORANGE (-2765 3710);
FORCEPROP 2 LASTPIN (-2775 3650) $PN AH73
J 0
(-2765 3660);
DISPLAY 0.617021 (-2765 3660);
PAINT ORANGE (-2765 3660);
FORCEPROP 2 LASTPIN (-2775 3550) $PN AJ20
J 0
(-2765 3560);
DISPLAY 0.617021 (-2765 3560);
PAINT ORANGE (-2765 3560);
FORCEPROP 2 LASTPIN (-2775 3500) $PN AJ56
J 0
(-2765 3510);
DISPLAY 0.617021 (-2765 3510);
PAINT ORANGE (-2765 3510);
FORCEPROP 2 LASTPIN (-2775 3450) $PN AJ58
J 0
(-2765 3460);
DISPLAY 0.617021 (-2765 3460);
PAINT ORANGE (-2765 3460);
FORCEPROP 2 LASTPIN (-2775 3400) $PN AJ60
J 0
(-2765 3410);
DISPLAY 0.617021 (-2765 3410);
PAINT ORANGE (-2765 3410);
FORCEPROP 2 LASTPIN (-2775 3350) $PN AJ62
J 0
(-2765 3360);
DISPLAY 0.617021 (-2765 3360);
PAINT ORANGE (-2765 3360);
FORCEPROP 2 LASTPIN (-2775 3300) $PN AJ70
J 0
(-2765 3310);
DISPLAY 0.617021 (-2765 3310);
PAINT ORANGE (-2765 3310);
FORCEPROP 2 LASTPIN (-2775 3250) $PN AK21
J 0
(-2765 3260);
DISPLAY 0.617021 (-2765 3260);
PAINT ORANGE (-2765 3260);
FORCEPROP 2 LASTPIN (-2775 2700) $PN AK27
J 0
(-2765 2710);
DISPLAY 0.617021 (-2765 2710);
PAINT ORANGE (-2765 2710);
FORCEPROP 2 LASTPIN (-2775 2550) $PN AK59
J 0
(-2765 2560);
DISPLAY 0.617021 (-2765 2560);
PAINT ORANGE (-2765 2560);
FORCEPROP 2 LASTPIN (-2775 2500) $PN AK61
J 0
(-2765 2510);
DISPLAY 0.617021 (-2765 2510);
PAINT ORANGE (-2765 2510);
FORCEPROP 2 LASTPIN (-2775 2250) $PN AK69
J 0
(-2765 2260);
DISPLAY 0.617021 (-2765 2260);
PAINT ORANGE (-2765 2260);
FORCEPROP 2 LASTPIN (-2775 2200) $PN AL20
J 0
(-2765 2210);
DISPLAY 0.617021 (-2765 2210);
PAINT ORANGE (-2765 2210);
FORCEPROP 2 LASTPIN (-2775 2000) $PN AL22
J 0
(-2765 2010);
DISPLAY 0.617021 (-2765 2010);
PAINT ORANGE (-2765 2010);
FORCEPROP 2 LASTPIN (-2775 1850) $PN AL26
J 0
(-2765 1860);
DISPLAY 0.617021 (-2765 1860);
PAINT ORANGE (-2765 1860);
FORCEPROP 2 LASTPIN (-2775 1800) $PN AL58
J 0
(-2765 1810);
DISPLAY 0.617021 (-2765 1810);
PAINT ORANGE (-2765 1810);
FORCEPROP 2 LASTPIN (-2775 1750) $PN AL60
J 0
(-2765 1760);
DISPLAY 0.617021 (-2765 1760);
PAINT ORANGE (-2765 1760);
FORCEPROP 2 LASTPIN (-2775 1700) $PN AL62
J 0
(-2765 1710);
DISPLAY 0.617021 (-2765 1710);
PAINT ORANGE (-2765 1710);
FORCEPROP 2 LASTPIN (-2775 1650) $PN AM21
J 0
(-2765 1660);
DISPLAY 0.617021 (-2765 1660);
PAINT ORANGE (-2765 1660);
FORCEPROP 2 LASTPIN (-2775 1550) $PN AM23
J 0
(-2765 1560);
DISPLAY 0.617021 (-2765 1560);
PAINT ORANGE (-2765 1560);
FORCEPROP 2 LASTPIN (-2775 1500) $PN AM25
J 0
(-2765 1510);
DISPLAY 0.617021 (-2765 1510);
PAINT ORANGE (-2765 1510);
FORCEPROP 2 LASTPIN (-2775 1450) $PN AM27
J 0
(-2765 1460);
DISPLAY 0.617021 (-2765 1460);
PAINT ORANGE (-2765 1460);
FORCEPROP 2 LASTPIN (-2775 1350) $PN AM61
J 0
(-2765 1360);
DISPLAY 0.617021 (-2765 1360);
PAINT ORANGE (-2765 1360);
FORCEPROP 2 LASTPIN (-2775 1300) $PN AN18
J 0
(-2765 1310);
DISPLAY 0.617021 (-2765 1310);
PAINT ORANGE (-2765 1310);
FORCEPROP 2 LASTPIN (-2775 1200) $PN AN22
J 0
(-2765 1210);
DISPLAY 0.617021 (-2765 1210);
PAINT ORANGE (-2765 1210);
FORCEPROP 2 LASTPIN (-2775 1050) $PN AN60
J 0
(-2765 1060);
DISPLAY 0.617021 (-2765 1060);
PAINT ORANGE (-2765 1060);
FORCEPROP 2 LASTPIN (-2775 1000) $PN AN62
J 0
(-2765 1010);
DISPLAY 0.617021 (-2765 1010);
PAINT ORANGE (-2765 1010);
FORCEPROP 2 LASTPIN (-2775 950) $PN AP23
J 0
(-2765 960);
DISPLAY 0.617021 (-2765 960);
PAINT ORANGE (-2765 960);
FORCEPROP 2 LASTPIN (-2775 900) $PN AP25
J 0
(-2765 910);
DISPLAY 0.617021 (-2765 910);
PAINT ORANGE (-2765 910);
FORCEPROP 2 LASTPIN (-2775 850) $PN AP27
J 0
(-2765 860);
DISPLAY 0.617021 (-2765 860);
PAINT ORANGE (-2765 860);
FORCEPROP 2 LASTPIN (-2775 800) $PN AP61
J 0
(-2765 810);
DISPLAY 0.617021 (-2765 810);
PAINT ORANGE (-2765 810);
FORCEPROP 2 LASTPIN (-2775 2650) $PN AU14
J 0
(-2765 2660);
DISPLAY 0.617021 (-2765 2660);
PAINT ORANGE (-2765 2660);
FORCEPROP 2 LASTPIN (-2775 2050) $PN AW12
J 0
(-2765 2060);
DISPLAY 0.617021 (-2765 2060);
PAINT ORANGE (-2765 2060);
FORCEPROP 2 LASTPIN (-2775 2450) $PN AV21
J 0
(-2765 2460);
DISPLAY 0.617021 (-2765 2460);
PAINT ORANGE (-2765 2460);
FORCEPROP 2 LASTPIN (-2775 1400) $PN AM59
J 0
(-2765 1410);
DISPLAY 0.617021 (-2765 1410);
PAINT ORANGE (-2765 1410);
FORCEPROP 2 LASTPIN (-2775 2850) $PN AP17
J 0
(-2765 2860);
DISPLAY 0.617021 (-2765 2860);
PAINT ORANGE (-2765 2860);
FORCEPROP 2 LASTPIN (-5275 4100) $PN B3
J 2
(-5285 4110);
DISPLAY 0.617021 (-5285 4110);
PAINT ORANGE (-5285 4110);
FORCEPROP 2 LASTPIN (-5275 3550) $PN C24
J 2
(-5285 3560);
DISPLAY 0.617021 (-5285 3560);
PAINT ORANGE (-5285 3560);
FORCEPROP 1 LAST PACK_TYPE BGA1
J 0
(-5225 4650);
PAINT SKYBLUE (-5225 4650);
DISPLAY INVISIBLE (-5225 4650);
FORCEPROP 2 LAST CDS_LIB chpset_lib
J 0
(-4025 2550);
PAINT ORANGE (-4025 2550);
DISPLAY INVISIBLE (-4025 2550);
FORCEPROP 2 LAST SEC_TYPE BGA1
J 0
(-5225 4650);
DISPLAY 1.021277 (-5225 4650);
PAINT ORANGE (-5225 4650);
DISPLAY INVISIBLE (-5225 4650);
FORCEPROP 2 LAST SEC 2
J 0
(-5225 4650);
DISPLAY 0.680851 (-5225 4650);
PAINT MONO (-5225 4650);
DISPLAY INVISIBLE (-5225 4650);
FORCEPROP 2 LAST CDS_LOCATION U2D1
J 0
(-5225 4600);
DISPLAY 0.617021 (-5225 4600);
PAINT AQUA (-5225 4600);
DISPLAY INVISIBLE (-5225 4600);
FORCEPROP 1 LAST PATH I169
J 0
(-4025 4550);
PAINT GREEN (-4025 4550);
DISPLAY INVISIBLE (-4025 4550);
FORCEADD GND..1
(-375 2425);
FORCEPROP 3 LASTPIN (-375 2475) SIG_NAME GND\g
J 0
(-365 2485);
DISPLAY 0.659574 (-365 2485);
PAINT MONO (-365 2485);
DISPLAY INVISIBLE (-365 2485);
FORCEPROP 1 LAST HDL_POWER GND
J 0
(-375 2575);
DISPLAY 0.702128 (-375 2575);
PAINT GREEN (-375 2575);
DISPLAY INVISIBLE (-375 2575);
FORCEPROP 1 LAST PATH I171
J 0
(-300 2425);
DISPLAY 0.872340 (-300 2425);
PAINT AQUA (-300 2425);
DISPLAY INVISIBLE (-300 2425);
FORCEPROP 1 LAST BODY_TYPE PLUMBING
J 0
(-420 2382);
DISPLAY 0.340426 (-420 2382);
PAINT GREEN (-420 2382);
DISPLAY INVISIBLE (-420 2382);
FORCEPROP 2 LAST CDS_LIB mstr_symbols
J 0
(-375 2425);
PAINT MONO (-375 2425);
DISPLAY INVISIBLE (-375 2425);
FORCEPROP 1 LAST SIZE 1B
J 0
(-300 2375);
DISPLAY 1.170213 (-300 2375);
PAINT GREEN (-300 2375);
DISPLAY INVISIBLE (-300 2375);
FORCEPROP 1 LAST VOLTAGE 0.0V
J 0
(-420 2382);
DISPLAY 0.340426 (-420 2382);
PAINT SKYBLUE (-420 2382);
DISPLAY INVISIBLE (-420 2382);
FORCEADD RES..2
(-650 2750);
FORCEPROP 1 LASTPIN (-650 2850) $PN 1
J 0
(-645 2812);
DISPLAY 0.617021 (-645 2812);
PAINT ORANGE (-645 2812);
FORCEPROP 1 LASTPIN (-650 2650) $PN 2
J 0
(-645 2660);
DISPLAY 0.617021 (-645 2660);
PAINT ORANGE (-645 2660);
FORCEPROP 1 LAST WATTAGE 1/16W
J 0
(-610 2725);
DISPLAY 0.617021 (-610 2725);
PAINT SKYBLUE (-610 2725);
FORCEPROP 1 LAST MATERIAL CHIP
J 0
(-610 2675);
DISPLAY 0.617021 (-610 2675);
PAINT SKYBLUE (-610 2675);
FORCEPROP 1 LAST PACK_TYPE 0402
J 0
(-610 2575);
DISPLAY 0.617021 (-610 2575);
PAINT SKYBLUE (-610 2575);
FORCEPROP 1 LAST TOLERANCE 1%
J 0
(-605 2775);
DISPLAY 0.617021 (-605 2775);
PAINT SKYBLUE (-605 2775);
FORCEPROP 1 LAST VALUE 49.9
J 0
(-605 2825);
DISPLAY 0.617021 (-605 2825);
PAINT SKYBLUE (-605 2825);
FORCEPROP 1 LAST LOCATION R8P3
J 0
(-605 2875);
DISPLAY 0.617021 (-605 2875);
PAINT AQUA (-605 2875);
FORCEPROP 1 LAST PART_NUMBER G21796-047
J 0
(-610 2625);
DISPLAY 0.617021 (-610 2625);
PAINT BLUE (-610 2625);
FORCEPROP 0 LAST ROOM CPU1
J 0
(-600 2975);
DISPLAY 1.021277 (-600 2975);
PAINT ORANGE (-600 2975);
DISPLAY INVISIBLE (-600 2975);
FORCEPROP 1 LAST PATH I173
J 0
(-600 2925);
DISPLAY 0.978723 (-600 2925);
PAINT WHITE (-600 2925);
DISPLAY INVISIBLE (-600 2925);
FORCEPROP 2 LAST CDS_LOCATION R8P3
J 0
(-605 2875);
DISPLAY 0.617021 (-605 2875);
PAINT AQUA (-605 2875);
DISPLAY INVISIBLE (-605 2875);
FORCEPROP 2 LAST SEC 1
J 0
(-600 2975);
DISPLAY 0.680851 (-600 2975);
PAINT MONO (-600 2975);
DISPLAY INVISIBLE (-600 2975);
FORCEPROP 2 LAST CDS_LIB mstr_discrete
J 0
(-650 2750);
PAINT MONO (-650 2750);
DISPLAY INVISIBLE (-650 2750);
FORCEPROP 2 LAST SEC_TYPE 0402
J 0
(-600 2975);
DISPLAY 1.021277 (-600 2975);
PAINT ORANGE (-600 2975);
DISPLAY INVISIBLE (-600 2975);
FORCEADD RES..2
(-375 2750);
FORCEPROP 1 LASTPIN (-375 2850) $PN 1
J 0
(-370 2812);
DISPLAY 0.617021 (-370 2812);
PAINT ORANGE (-370 2812);
FORCEPROP 1 LASTPIN (-375 2650) $PN 2
J 0
(-370 2660);
DISPLAY 0.617021 (-370 2660);
PAINT ORANGE (-370 2660);
FORCEPROP 1 LAST WATTAGE 1/16W
J 0
(-335 2725);
DISPLAY 0.617021 (-335 2725);
PAINT SKYBLUE (-335 2725);
FORCEPROP 1 LAST MATERIAL CHIP
J 0
(-335 2675);
DISPLAY 0.617021 (-335 2675);
PAINT SKYBLUE (-335 2675);
FORCEPROP 1 LAST PACK_TYPE 0402
J 0
(-335 2575);
DISPLAY 0.617021 (-335 2575);
PAINT SKYBLUE (-335 2575);
FORCEPROP 1 LAST TOLERANCE 1%
J 0
(-330 2775);
DISPLAY 0.617021 (-330 2775);
PAINT SKYBLUE (-330 2775);
FORCEPROP 1 LAST VALUE 49.9
J 0
(-330 2825);
DISPLAY 0.617021 (-330 2825);
PAINT SKYBLUE (-330 2825);
FORCEPROP 1 LAST PART_NUMBER G21796-047
J 0
(-335 2625);
DISPLAY 0.617021 (-335 2625);
PAINT BLUE (-335 2625);
FORCEPROP 1 LAST LOCATION R8R1
J 0
(-330 2875);
DISPLAY 0.617021 (-330 2875);
PAINT AQUA (-330 2875);
FORCEPROP 0 LAST ROOM CPU1
J 0
(-325 2975);
DISPLAY 1.021277 (-325 2975);
PAINT ORANGE (-325 2975);
DISPLAY INVISIBLE (-325 2975);
FORCEPROP 1 LAST PATH I174
J 0
(-325 2925);
DISPLAY 0.978723 (-325 2925);
PAINT WHITE (-325 2925);
DISPLAY INVISIBLE (-325 2925);
FORCEPROP 2 LAST CDS_LOCATION R8R1
J 0
(-330 2875);
DISPLAY 0.617021 (-330 2875);
PAINT AQUA (-330 2875);
DISPLAY INVISIBLE (-330 2875);
FORCEPROP 2 LAST SEC 1
J 0
(-325 2975);
DISPLAY 0.680851 (-325 2975);
PAINT MONO (-325 2975);
DISPLAY INVISIBLE (-325 2975);
FORCEPROP 2 LAST SEC_TYPE 0402
J 0
(-325 2975);
DISPLAY 1.021277 (-325 2975);
PAINT ORANGE (-325 2975);
DISPLAY INVISIBLE (-325 2975);
FORCEPROP 2 LAST CDS_LIB mstr_discrete
J 0
(-375 2750);
PAINT MONO (-375 2750);
DISPLAY INVISIBLE (-375 2750);
FORCEADD OFFPAGE..4
(-1550 1450);
FORCEPROP 2 LAST $XR0 103 
J 0
(-1364 1450);
DISPLAY 0.638298 (-1364 1450);
PAINT MONO (-1364 1450);
FORCEPROP 2 LAST CDS_LIB mstr_standard
J 0
(-1550 1450);
PAINT MONO (-1550 1450);
DISPLAY INVISIBLE (-1550 1450);
FORCEPROP 1 LAST OFFPAGE TRUE
J 0
(-1225 1325);
DISPLAY 0.872340 (-1225 1325);
PAINT GREEN (-1225 1325);
DISPLAY INVISIBLE (-1225 1325);
FORCEPROP 1 LAST COMMENT_BODY TRUE
J 0
(-1575 1350);
DISPLAY 0.872340 (-1575 1350);
PAINT GREEN (-1575 1350);
DISPLAY INVISIBLE (-1575 1350);
FORCEPROP 2 LAST PATH I178
J 0
(-1375 1525);
DISPLAY 1.021277 (-1375 1525);
PAINT ORANGE (-1375 1525);
DISPLAY INVISIBLE (-1375 1525);
FORCEADD OFFPAGE..4
(-1550 850);
FORCEPROP 2 LAST $XR0 103 
J 0
(-1364 850);
DISPLAY 0.638298 (-1364 850);
PAINT MONO (-1364 850);
FORCEPROP 2 LAST PATH I179
J 0
(-1375 925);
DISPLAY 1.021277 (-1375 925);
PAINT ORANGE (-1375 925);
DISPLAY INVISIBLE (-1375 925);
FORCEPROP 1 LAST COMMENT_BODY TRUE
J 0
(-1575 750);
DISPLAY 0.872340 (-1575 750);
PAINT GREEN (-1575 750);
DISPLAY INVISIBLE (-1575 750);
FORCEPROP 1 LAST OFFPAGE TRUE
J 0
(-1225 725);
DISPLAY 0.872340 (-1225 725);
PAINT GREEN (-1225 725);
DISPLAY INVISIBLE (-1225 725);
FORCEPROP 2 LAST CDS_LIB mstr_standard
J 0
(-1550 850);
PAINT MONO (-1550 850);
DISPLAY INVISIBLE (-1550 850);
FORCEADD OFFPAGE..2
(-1550 1850);
FORCEPROP 2 LAST $XR0 104 
J 0
(-1361 1850);
DISPLAY 0.638298 (-1361 1850);
PAINT MONO (-1361 1850);
FORCEPROP 2 LAST PATH I180
J 0
(-1350 1900);
DISPLAY 1.021277 (-1350 1900);
PAINT ORANGE (-1350 1900);
DISPLAY INVISIBLE (-1350 1900);
FORCEPROP 1 LAST COMMENT_BODY TRUE
J 0
(-1595 1755);
DISPLAY 0.936170 (-1595 1755);
PAINT PEACH (-1595 1755);
DISPLAY INVISIBLE (-1595 1755);
FORCEPROP 1 LAST OFFPAGE TRUE
J 0
(-1225 1725);
DISPLAY 0.489362 (-1225 1725);
PAINT GREEN (-1225 1725);
DISPLAY INVISIBLE (-1225 1725);
FORCEPROP 2 LAST CDS_LIB mstr_standard
J 0
(-1550 1850);
PAINT ORANGE (-1550 1850);
DISPLAY INVISIBLE (-1550 1850);
FORCEADD OFFPAGE..4
(-1550 2050);
FORCEPROP 2 LAST $XR0 90 
J 0
(-1364 2050);
DISPLAY 0.638298 (-1364 2050);
PAINT MONO (-1364 2050);
FORCEPROP 2 LAST PATH I181
J 0
(-1350 2100);
DISPLAY 1.021277 (-1350 2100);
PAINT ORANGE (-1350 2100);
DISPLAY INVISIBLE (-1350 2100);
FORCEPROP 1 LAST COMMENT_BODY TRUE
J 0
(-1575 1950);
DISPLAY 0.680851 (-1575 1950);
PAINT PEACH (-1575 1950);
DISPLAY INVISIBLE (-1575 1950);
FORCEPROP 1 LAST OFFPAGE TRUE
J 0
(-1225 1925);
DISPLAY 0.680851 (-1225 1925);
PAINT GREEN (-1225 1925);
DISPLAY INVISIBLE (-1225 1925);
FORCEPROP 2 LAST CDS_LIB mstr_standard
J 0
(-1550 2050);
DISPLAY 0.489362 (-1550 2050);
PAINT ORANGE (-1550 2050);
DISPLAY INVISIBLE (-1550 2050);
FORCEADD OFFPAGE..4
(-1550 2700);
FORCEPROP 2 LAST $XR0 104 
J 0
(-1364 2700);
DISPLAY 0.638298 (-1364 2700);
PAINT MONO (-1364 2700);
FORCEPROP 2 LAST PATH I182
J 0
(-1350 2750);
DISPLAY 1.021277 (-1350 2750);
PAINT ORANGE (-1350 2750);
DISPLAY INVISIBLE (-1350 2750);
FORCEPROP 1 LAST COMMENT_BODY TRUE
J 0
(-1575 2600);
DISPLAY 0.680851 (-1575 2600);
PAINT PEACH (-1575 2600);
DISPLAY INVISIBLE (-1575 2600);
FORCEPROP 1 LAST OFFPAGE TRUE
J 0
(-1225 2575);
DISPLAY 0.680851 (-1225 2575);
PAINT GREEN (-1225 2575);
DISPLAY INVISIBLE (-1225 2575);
FORCEPROP 2 LAST CDS_LIB mstr_standard
J 0
(-1550 2700);
PAINT ORANGE (-1550 2700);
DISPLAY INVISIBLE (-1550 2700);
FORCEADD OFFPAGE..2
(-1550 2650);
FORCEPROP 2 LAST $XR0 92 
J 0
(-1361 2650);
DISPLAY 0.638298 (-1361 2650);
PAINT MONO (-1361 2650);
FORCEPROP 2 LAST CDS_LIB mstr_standard
J 0
(-1550 2650);
DISPLAY 0.787234 (-1550 2650);
PAINT MONO (-1550 2650);
DISPLAY INVISIBLE (-1550 2650);
FORCEPROP 1 LAST OFFPAGE TRUE
J 0
(-1225 2525);
DISPLAY 0.489362 (-1225 2525);
PAINT GREEN (-1225 2525);
DISPLAY INVISIBLE (-1225 2525);
FORCEPROP 1 LAST COMMENT_BODY TRUE
J 0
(-1595 2555);
DISPLAY 0.936170 (-1595 2555);
PAINT PEACH (-1595 2555);
DISPLAY INVISIBLE (-1595 2555);
FORCEPROP 2 LAST PATH I183
J 0
(-1350 2700);
DISPLAY 1.021277 (-1350 2700);
PAINT ORANGE (-1350 2700);
DISPLAY INVISIBLE (-1350 2700);
FORCEADD VCC_CORE..1
(-950 2300);
FORCEPROP 3 LASTPIN (-950 2250) SIG_NAME PVCCMCP_CPU1\g
J 0
(-940 2260);
DISPLAY 0.659574 (-940 2260);
PAINT MONO (-940 2260);
DISPLAY INVISIBLE (-940 2260);
FORCEPROP 1 LAST HDL_POWER PVCCMCP_CPU1
J 1
(-950 2350);
DISPLAY 0.617021 (-950 2350);
PAINT GREEN (-950 2350);
FORCEPROP 1 LAST PATH I185
J 0
(-900 2325);
DISPLAY 0.872340 (-900 2325);
PAINT AQUA (-900 2325);
DISPLAY INVISIBLE (-900 2325);
FORCEPROP 2 LAST CDS_LIB mstr_symbols
J 0
(-950 2300);
PAINT ORANGE (-950 2300);
DISPLAY INVISIBLE (-950 2300);
FORCEADD OFFPAGE..2
R 2
(-7100 1750);
FORCEPROP 2 LAST $XR2 145 
J 0
(-7595 1750);
DISPLAY 0.638298 (-7595 1750);
PAINT MONO (-7595 1750);
FORCEPROP 2 LAST $XR1 120 
J 0
(-7475 1750);
DISPLAY 0.638298 (-7475 1750);
PAINT MONO (-7475 1750);
FORCEPROP 2 LAST $XR0 133 
J 0
(-7355 1750);
DISPLAY 0.638298 (-7355 1750);
PAINT MONO (-7355 1750);
FORCEPROP 2 LAST CDS_LIB mstr_standard
J 2
(-7100 1750);
PAINT ORANGE (-7100 1750);
DISPLAY INVISIBLE (-7100 1750);
FORCEPROP 1 LAST OFFPAGE TRUE
J 2
(-7425 1625);
DISPLAY 0.489362 (-7425 1625);
PAINT GREEN (-7425 1625);
DISPLAY INVISIBLE (-7425 1625);
FORCEPROP 1 LAST COMMENT_BODY TRUE
J 2
(-7055 1655);
DISPLAY 0.936170 (-7055 1655);
PAINT PEACH (-7055 1655);
DISPLAY INVISIBLE (-7055 1655);
FORCEPROP 2 LAST PATH I187
J 2
(-7275 1825);
DISPLAY 1.021277 (-7275 1825);
PAINT ORANGE (-7275 1825);
DISPLAY INVISIBLE (-7275 1825);
FORCEADD VCC_CORE..1
(-7250 4350);
FORCEPROP 3 LASTPIN (-7250 4300) SIG_NAME P1V8_MCP_CPU1\g
J 0
(-7240 4310);
DISPLAY 0.659574 (-7240 4310);
PAINT MONO (-7240 4310);
DISPLAY INVISIBLE (-7240 4310);
FORCEPROP 1 LAST HDL_POWER P1V8_MCP_CPU1
J 1
(-7250 4400);
DISPLAY 0.617021 (-7250 4400);
PAINT GREEN (-7250 4400);
FORCEPROP 0 LAST VOLTAGE 1.8
J 0
(-7250 4500);
DISPLAY 1.021277 (-7250 4500);
PAINT SKYBLUE (-7250 4500);
DISPLAY INVISIBLE (-7250 4500);
FORCEPROP 2 LAST CDS_LIB mstr_symbols
J 0
(-7250 4350);
PAINT ORANGE (-7250 4350);
DISPLAY INVISIBLE (-7250 4350);
FORCEPROP 1 LAST PATH I188
J 0
(-7200 4375);
DISPLAY 0.872340 (-7200 4375);
PAINT AQUA (-7200 4375);
DISPLAY INVISIBLE (-7200 4375);
FORCEADD OFFPAGE..4
(-1550 3250);
FORCEPROP 2 LAST $XR0 193 
J 0
(-1364 3250);
DISPLAY 0.638298 (-1364 3250);
PAINT MONO (-1364 3250);
FORCEPROP 2 LAST PATH I189
J 0
(-1375 3325);
DISPLAY 1.021277 (-1375 3325);
PAINT ORANGE (-1375 3325);
DISPLAY INVISIBLE (-1375 3325);
FORCEPROP 1 LAST COMMENT_BODY TRUE
J 0
(-1575 3150);
DISPLAY 0.680851 (-1575 3150);
PAINT PEACH (-1575 3150);
DISPLAY INVISIBLE (-1575 3150);
FORCEPROP 1 LAST OFFPAGE TRUE
J 0
(-1225 3125);
DISPLAY 0.680851 (-1225 3125);
PAINT GREEN (-1225 3125);
DISPLAY INVISIBLE (-1225 3125);
FORCEPROP 2 LAST CDS_LIB mstr_standard
J 0
(-1550 3250);
PAINT ORANGE (-1550 3250);
DISPLAY INVISIBLE (-1550 3250);
FORCEADD OFFPAGE..4
(-1550 2200);
FORCEPROP 2 LAST $XR0 193 
J 0
(-1364 2200);
DISPLAY 0.638298 (-1364 2200);
PAINT MONO (-1364 2200);
FORCEPROP 2 LAST PATH I190
J 0
(-1375 2275);
DISPLAY 1.021277 (-1375 2275);
PAINT ORANGE (-1375 2275);
DISPLAY INVISIBLE (-1375 2275);
FORCEPROP 1 LAST COMMENT_BODY TRUE
J 0
(-1575 2100);
DISPLAY 0.680851 (-1575 2100);
PAINT PEACH (-1575 2100);
DISPLAY INVISIBLE (-1575 2100);
FORCEPROP 1 LAST OFFPAGE TRUE
J 0
(-1225 2075);
DISPLAY 0.680851 (-1225 2075);
PAINT GREEN (-1225 2075);
DISPLAY INVISIBLE (-1225 2075);
FORCEPROP 2 LAST CDS_LIB mstr_standard
J 0
(-1550 2200);
PAINT ORANGE (-1550 2200);
DISPLAY INVISIBLE (-1550 2200);
FORCEADD INTEL_CORP_BPAGE..1
(0 0);
FORCEPROP 1 LAST CDS_CON_LAST_MODIFIED Fri Jun 16 17:48:22 2017
J 0
(-1425 325);
DISPLAY 1.340426 (-1425 325);
PAINT GREEN (-1425 325);
DISPLAY INVISIBLE (-1425 325);
FORCEPROP 1 LAST CUSTOM_TXT_CDS <CURRENT_DESIGN_SHEET> OF <TOTAL_DESIGN_SHEETS>
J 0
(-500 25);
PAINT ORANGE (-500 25);
FORCEPROP 1 LAST CUSTOM_TXT_CDS <CON_LAST_MODIFIED>
J 0
(-4000 100);
PAINT ORANGE (-4000 100);
FORCEPROP 2 LAST CUSTOM_TXT_CDS <XR_PAGE_TITLE>
J 0
(-7890 5250);
DISPLAY 0.638298 (-7890 5250);
PAINT PINK (-7890 5250);
DISPLAY INVISIBLE (-7890 5250);
FORCEPROP 1 LAST SCH_TITLE SKYLAKE - SKT1 - 2 OF 21
J 0
(-7950 50);
DISPLAY 1.212766 (-7950 50);
PAINT GREEN (-7950 50);
FORCEPROP 2 LAST PAGE_BORDER TRUE
J 0
(-7890 5250);
DISPLAY 0.851064 (-7890 5250);
PAINT PINK (-7890 5250);
DISPLAY INVISIBLE (-7890 5250);
FORCEPROP 2 LAST CDS_LIB mstr_symbols
J 0
(0 0);
PAINT ORANGE (0 0);
DISPLAY INVISIBLE (0 0);
FORCEPROP 1 LAST COMMENT_BODY TRUE
J 0
(12 12);
DISPLAY 0.638298 (12 12);
PAINT GREEN (12 12);
DISPLAY INVISIBLE (12 12);
FORCEPROP 2 LAST CDS_XR_PAGE_TITLE CR-56 : @BASEBOARD_FAB2_LIB.BASEBOARD_FAB2(SCH_1):PAGE56
J 0
(-7890 5250);
DISPLAY 0.638298 (-7890 5250);
PAINT PINK (-7890 5250);
DISPLAY INVISIBLE (-7890 5250);
FORCEADD PRELIM..10
(-4240 2590);
PAINT GRAY (-4240 2590);
FORCEPROP 2 LAST CDS_LIB mstr_misc
J 0
(-4240 2590);
PAINT ORANGE (-4240 2590);
DISPLAY INVISIBLE (-4240 2590);
FORCEPROP 1 LAST COMMENT_BODY TRUE
J 0
(-4240 2590);
PAINT ORANGE (-4240 2590);
DISPLAY INVISIBLE (-4240 2590);
FORCEADD DESIGN_NOTE..1
(-5025 450);
FORCEPROP 0 LAST L1 CPU SYMBOLS 1-30 ARE PRELIMINARY AND SUBJECT TO CHANGE
J 0
(-5225 325);
DISPLAY 1.021277 (-5225 325);
PAINT ORANGE (-5225 325);
FORCEPROP 2 LAST CDS_LIB mstr_symbols
J 0
(-5025 450);
PAINT ORANGE (-5025 450);
DISPLAY INVISIBLE (-5025 450);
FORCEPROP 1 LAST COMMENT_BODY TRUE
J 0
(-5000 550);
DISPLAY 0.978723 (-5000 550);
PAINT ORANGE (-5000 550);
DISPLAY INVISIBLE (-5000 550);
FORCEADD DESIGN_NOTE..1
(-600 1725);
FORCEPROP 0 LAST L1 CLKS USED FOR DEBUG ONLY
J 0
(-775 1600);
DISPLAY 0.808511 (-775 1600);
PAINT ORANGE (-775 1600);
FORCEPROP 2 LAST CDS_LIB mstr_symbols
J 0
(-600 1725);
PAINT ORANGE (-600 1725);
DISPLAY INVISIBLE (-600 1725);
FORCEPROP 1 LAST COMMENT_BODY TRUE
J 0
(-575 1825);
DISPLAY 0.978723 (-575 1825);
PAINT ORANGE (-575 1825);
DISPLAY INVISIBLE (-575 1825);
WIRE 16 -1 (-375 2525)(-375 2475);
WIRE 16 -1 (-650 2525)(-375 2525);
WIRE 16 -1 (-375 2650)(-375 2525);
WIRE 16 -1 (-650 2650)(-650 2525);
WIRE 16 -1 (-950 1650)(-950 2250);
WIRE 16 -1 (-950 1500)(-950 1650);
WIRE 16 -1 (-2775 1650)(-950 1650);
WIRE 16 -1 (-950 1100)(-950 1500);
WIRE 16 -1 (-2775 1500)(-950 1500);
WIRE 16 -1 (-2600 1100)(-950 1100);
WIRE 16 -1 (-950 900)(-950 1100);
WIRE 16 -1 (-2600 900)(-950 900);
WIRE 16 -1 (-2600 1150)(-2600 1100);
WIRE 16 -1 (-2775 1100)(-2600 1100);
WIRE 16 -1 (-2600 1200)(-2600 1150);
WIRE 16 -1 (-2775 1150)(-2600 1150);
WIRE 16 -1 (-2600 950)(-2600 900);
WIRE 16 -1 (-2775 900)(-2600 900);
WIRE 16 -1 (-2775 950)(-2600 950);
WIRE 16 -1 (-2600 1300)(-2600 1200);
WIRE 16 -1 (-2775 1200)(-2600 1200);
WIRE 16 -1 (-2775 1300)(-2600 1300);
WIRE 16 -1 (-7250 4300)(-7250 4250);
WIRE 16 -1 (-7250 3950)(-7250 4250);
WIRE 16 -1 (-7250 4250)(-5450 4250);
WIRE 16 -1 (-5450 4200)(-5450 4250);
WIRE 16 -1 (-5450 4250)(-5275 4250);
WIRE 16 -1 (-5450 3950)(-7250 3950);
WIRE 16 -1 (-5450 3900)(-5450 3950);
WIRE 16 -1 (-5275 3950)(-5450 3950);
WIRE 16 -1 (-5275 4200)(-5450 4200);
WIRE 16 -1 (-5450 3850)(-5450 3900);
WIRE 16 -1 (-5275 3900)(-5450 3900);
WIRE 16 -1 (-5275 3850)(-5450 3850);
WIRE 16 -1 (-5275 3500)(-6325 3500);
FORCEPROP 2 LAST SIG_NAME TP_CPU1_RSVD_288
J 0
(-6300 3510);
DISPLAY 0.617021 (-6300 3510);
PAINT ORANGE (-6300 3510);
FORCEPROP 2 LASTPROP $XRERR UNIQUE?
J 0
(-6565 3500);
DISPLAY 0.638298 (-6565 3500);
PAINT MONO (-6565 3500);
DISPLAY INVISIBLE (-6565 3500);
WIRE 16 -1 (-1600 2600)(-2775 2600);
FORCEPROP 2 LAST SIG_NAME TP_CPU1_RSVD_219
J 0
(-2600 2610);
DISPLAY 0.617021 (-2600 2610);
PAINT ORANGE (-2600 2610);
FORCEPROP 2 LASTPROP $XRERR UNIQUE?
J 0
(-1570 2600);
DISPLAY 0.638298 (-1570 2600);
PAINT MONO (-1570 2600);
DISPLAY INVISIBLE (-1570 2600);
WIRE 16 -1 (-1600 1750)(-2775 1750);
FORCEPROP 2 LAST SIG_NAME TP_CPU1_RSVD_211
J 0
(-2600 1760);
DISPLAY 0.617021 (-2600 1760);
PAINT ORANGE (-2600 1760);
FORCEPROP 2 LASTPROP $XRERR UNIQUE?
J 0
(-1570 1750);
DISPLAY 0.638298 (-1570 1750);
PAINT MONO (-1570 1750);
DISPLAY INVISIBLE (-1570 1750);
WIRE 16 -1 (-1600 3350)(-2775 3350);
FORCEPROP 2 LAST SIG_NAME TP_CPU1_RSVD_223
J 0
(-2600 3360);
DISPLAY 0.617021 (-2600 3360);
PAINT ORANGE (-2600 3360);
FORCEPROP 2 LASTPROP $XRERR UNIQUE?
J 0
(-1570 3350);
DISPLAY 0.638298 (-1570 3350);
PAINT MONO (-1570 3350);
DISPLAY INVISIBLE (-1570 3350);
WIRE 16 -1 (-5275 4050)(-6325 4050);
FORCEPROP 2 LAST SIG_NAME TP_CPU1_RSVD_298
J 0
(-6300 4060);
DISPLAY 0.617021 (-6300 4060);
PAINT ORANGE (-6300 4060);
FORCEPROP 2 LASTPROP $XRERR UNIQUE?
J 0
(-6565 4050);
DISPLAY 0.638298 (-6565 4050);
PAINT MONO (-6565 4050);
DISPLAY INVISIBLE (-6565 4050);
WIRE 16 -1 (-1600 2450)(-2775 2450);
FORCEPROP 2 LAST SIG_NAME CPU_XDP_PRESENT_N
J 0
(-2600 2460);
DISPLAY 0.617021 (-2600 2460);
PAINT ORANGE (-2600 2460);
WIRE 16 -1 (-1600 2500)(-2775 2500);
FORCEPROP 2 LAST SIG_NAME TP_CPU1_RSVD_217
J 0
(-2600 2510);
DISPLAY 0.617021 (-2600 2510);
PAINT ORANGE (-2600 2510);
FORCEPROP 2 LASTPROP $XRERR UNIQUE?
J 0
(-1570 2500);
DISPLAY 0.638298 (-1570 2500);
PAINT MONO (-1570 2500);
DISPLAY INVISIBLE (-1570 2500);
WIRE 16 -1 (-1600 2550)(-2775 2550);
FORCEPROP 2 LAST SIG_NAME TP_CPU1_RSVD_218
J 0
(-2600 2560);
DISPLAY 0.617021 (-2600 2560);
PAINT ORANGE (-2600 2560);
FORCEPROP 2 LASTPROP $XRERR UNIQUE?
J 0
(-1570 2550);
DISPLAY 0.638298 (-1570 2550);
PAINT MONO (-1570 2550);
DISPLAY INVISIBLE (-1570 2550);
WIRE 16 -1 (-1600 2650)(-2775 2650);
FORCEPROP 2 LAST SIG_NAME H_CPU1_FIVR_FAULT_G
J 0
(-2600 2660);
DISPLAY 0.617021 (-2600 2660);
PAINT ORANGE (-2600 2660);
WIRE 16 -1 (-1600 2700)(-2775 2700);
FORCEPROP 2 LAST SIG_NAME CLK_322M_OSC_CPU1_RC_DP
J 0
(-2610 2710);
DISPLAY 0.617021 (-2610 2710);
PAINT ORANGE (-2610 2710);
WIRE 16 -1 (-1600 2350)(-2775 2350);
FORCEPROP 2 LAST SIG_NAME TP_CPU1_RSVD_TEST_5
J 0
(-2600 2360);
DISPLAY 0.617021 (-2600 2360);
PAINT ORANGE (-2600 2360);
FORCEPROP 2 LASTPROP $XRERR UNIQUE?
J 0
(-1570 2350);
DISPLAY 0.638298 (-1570 2350);
PAINT MONO (-1570 2350);
DISPLAY INVISIBLE (-1570 2350);
WIRE 16 -1 (-1600 2250)(-2775 2250);
FORCEPROP 2 LAST SIG_NAME TP_CPU1_RSVD_216
J 0
(-2600 2260);
DISPLAY 0.617021 (-2600 2260);
PAINT ORANGE (-2600 2260);
FORCEPROP 2 LASTPROP $XRERR UNIQUE?
J 0
(-1570 2250);
DISPLAY 0.638298 (-1570 2250);
PAINT MONO (-1570 2250);
DISPLAY INVISIBLE (-1570 2250);
WIRE 16 -1 (-6325 3250)(-5275 3250);
FORCEPROP 2 LAST SIG_NAME TP_CPU1_RSVD_283
J 0
(-6300 3260);
DISPLAY 0.617021 (-6300 3260);
PAINT ORANGE (-6300 3260);
FORCEPROP 2 LASTPROP $XRERR UNIQUE?
J 0
(-6565 3250);
DISPLAY 0.638298 (-6565 3250);
PAINT MONO (-6565 3250);
DISPLAY INVISIBLE (-6565 3250);
WIRE 16 -1 (-5275 3400)(-6325 3400);
FORCEPROP 2 LAST SIG_NAME TP_CPU1_RSVD_286
J 0
(-6300 3410);
DISPLAY 0.617021 (-6300 3410);
PAINT ORANGE (-6300 3410);
FORCEPROP 2 LASTPROP $XRERR UNIQUE?
J 0
(-6565 3400);
DISPLAY 0.638298 (-6565 3400);
PAINT MONO (-6565 3400);
DISPLAY INVISIBLE (-6565 3400);
WIRE 16 -1 (-1600 3650)(-2775 3650);
FORCEPROP 2 LAST SIG_NAME TP_CPU1_RSVD_228
J 0
(-2600 3660);
DISPLAY 0.617021 (-2600 3660);
PAINT ORANGE (-2600 3660);
FORCEPROP 2 LASTPROP $XRERR UNIQUE?
J 0
(-1570 3650);
DISPLAY 0.638298 (-1570 3650);
PAINT MONO (-1570 3650);
DISPLAY INVISIBLE (-1570 3650);
WIRE 16 -1 (-2775 2200)(-1600 2200);
FORCEPROP 2 LAST SIG_NAME VSENSE_P1V8MCP_CPU1_SKT_VRTN
J 0
(-2602 2208);
DISPLAY 0.617021 (-2602 2208);
PAINT ORANGE (-2602 2208);
WIRE 16 -1 (-1600 2850)(-2775 2850);
FORCEPROP 2 LAST SIG_NAME XDP_CPU_PWR_DEBUG_N
J 0
(-2600 2860);
DISPLAY 0.617021 (-2600 2860);
PAINT ORANGE (-2600 2860);
WIRE 16 -1 (-1600 2950)(-2775 2950);
FORCEPROP 2 LAST SIG_NAME TP_CPU1_RSVD_TEST_4
J 0
(-2575 2960);
DISPLAY 0.617021 (-2575 2960);
PAINT ORANGE (-2575 2960);
FORCEPROP 2 LASTPROP $XRERR UNIQUE?
J 0
(-1570 2950);
DISPLAY 0.638298 (-1570 2950);
PAINT MONO (-1570 2950);
DISPLAY INVISIBLE (-1570 2950);
WIRE 16 -1 (-1600 1400)(-2775 1400);
FORCEPROP 2 LAST SIG_NAME TP_CPU1_RSVD_205
J 0
(-2600 1410);
DISPLAY 0.617021 (-2600 1410);
PAINT ORANGE (-2600 1410);
FORCEPROP 2 LASTPROP $XRERR UNIQUE?
J 0
(-1570 1400);
DISPLAY 0.638298 (-1570 1400);
PAINT MONO (-1570 1400);
DISPLAY INVISIBLE (-1570 1400);
WIRE 16 -1 (-1600 1350)(-2775 1350);
FORCEPROP 2 LAST SIG_NAME TP_CPU1_RSVD_204
J 0
(-2600 1360);
DISPLAY 0.617021 (-2600 1360);
PAINT ORANGE (-2600 1360);
FORCEPROP 2 LASTPROP $XRERR UNIQUE?
J 0
(-1570 1350);
DISPLAY 0.638298 (-1570 1350);
PAINT MONO (-1570 1350);
DISPLAY INVISIBLE (-1570 1350);
WIRE 16 -1 (-650 3050)(-2775 3050);
FORCEPROP 2 LAST SIG_NAME PD_CPU1_RSVD_TEST_2
J 0
(-2575 3060);
DISPLAY 0.617021 (-2575 3060);
PAINT ORANGE (-2575 3060);
FORCEPROP 2 LASTPROP $XRERR UNIQUE?
J 0
(-2815 3060);
DISPLAY 0.638298 (-2815 3060);
PAINT MONO (-2815 3060);
DISPLAY INVISIBLE (-2815 3060);
WIRE 16 -1 (-650 2850)(-650 3050);
WIRE 16 -1 (-375 3100)(-2775 3100);
FORCEPROP 2 LAST SIG_NAME PD_CPU1_RSVD_TEST_1
J 0
(-2575 3110);
DISPLAY 0.617021 (-2575 3110);
PAINT ORANGE (-2575 3110);
FORCEPROP 2 LASTPROP $XRERR UNIQUE?
J 0
(-2815 3110);
DISPLAY 0.638298 (-2815 3110);
PAINT MONO (-2815 3110);
DISPLAY INVISIBLE (-2815 3110);
WIRE 16 -1 (-375 2850)(-375 3100);
WIRE 16 -1 (-5275 3650)(-6325 3650);
FORCEPROP 2 LAST SIG_NAME TP_CPU1_RSVD_290
J 0
(-6300 3660);
DISPLAY 0.617021 (-6300 3660);
PAINT ORANGE (-6300 3660);
FORCEPROP 2 LASTPROP $XRERR UNIQUE?
J 0
(-6565 3650);
DISPLAY 0.638298 (-6565 3650);
PAINT MONO (-6565 3650);
DISPLAY INVISIBLE (-6565 3650);
WIRE 16 -1 (-5275 3450)(-6325 3450);
FORCEPROP 2 LAST SIG_NAME TP_CPU1_RSVD_287
J 0
(-6300 3460);
DISPLAY 0.617021 (-6300 3460);
PAINT ORANGE (-6300 3460);
FORCEPROP 2 LASTPROP $XRERR UNIQUE?
J 0
(-6565 3450);
DISPLAY 0.638298 (-6565 3450);
PAINT MONO (-6565 3450);
DISPLAY INVISIBLE (-6565 3450);
WIRE 16 -1 (-5275 3350)(-6325 3350);
FORCEPROP 2 LAST SIG_NAME TP_CPU1_RSVD_285
J 0
(-6300 3360);
DISPLAY 0.617021 (-6300 3360);
PAINT ORANGE (-6300 3360);
FORCEPROP 2 LASTPROP $XRERR UNIQUE?
J 0
(-6565 3350);
DISPLAY 0.638298 (-6565 3350);
PAINT MONO (-6565 3350);
DISPLAY INVISIBLE (-6565 3350);
WIRE 16 -1 (-6300 1500)(-5275 1500);
FORCEPROP 2 LAST SIG_NAME TP_CPU1_RSVD_254
J 0
(-6300 1510);
DISPLAY 0.617021 (-6300 1510);
PAINT ORANGE (-6300 1510);
FORCEPROP 2 LASTPROP $XRERR UNIQUE?
J 0
(-6540 1500);
DISPLAY 0.638298 (-6540 1500);
PAINT MONO (-6540 1500);
DISPLAY INVISIBLE (-6540 1500);
WIRE 16 -1 (-5275 2100)(-6325 2100);
FORCEPROP 2 LAST SIG_NAME TP_CPU1_RSVD_263
J 0
(-6300 2110);
DISPLAY 0.617021 (-6300 2110);
PAINT ORANGE (-6300 2110);
FORCEPROP 2 LASTPROP $XRERR UNIQUE?
J 0
(-6565 2100);
DISPLAY 0.638298 (-6565 2100);
PAINT MONO (-6565 2100);
DISPLAY INVISIBLE (-6565 2100);
WIRE 16 -1 (-5275 2150)(-6325 2150);
FORCEPROP 2 LAST SIG_NAME TP_CPU1_RSVD_264
J 0
(-6300 2160);
DISPLAY 0.617021 (-6300 2160);
PAINT ORANGE (-6300 2160);
FORCEPROP 2 LASTPROP $XRERR UNIQUE?
J 0
(-6565 2150);
DISPLAY 0.638298 (-6565 2150);
PAINT MONO (-6565 2150);
DISPLAY INVISIBLE (-6565 2150);
WIRE 16 -1 (-5275 2850)(-6325 2850);
FORCEPROP 2 LAST SIG_NAME TP_CPU1_RSVD_277
J 0
(-6300 2860);
DISPLAY 0.617021 (-6300 2860);
PAINT ORANGE (-6300 2860);
FORCEPROP 2 LASTPROP $XRERR UNIQUE?
J 0
(-6565 2850);
DISPLAY 0.638298 (-6565 2850);
PAINT MONO (-6565 2850);
DISPLAY INVISIBLE (-6565 2850);
WIRE 16 -1 (-1600 2000)(-2775 2000);
FORCEPROP 2 LAST SIG_NAME TP_CPU1_RSVD_214
J 0
(-2600 2010);
DISPLAY 0.617021 (-2600 2010);
PAINT ORANGE (-2600 2010);
FORCEPROP 2 LASTPROP $XRERR UNIQUE?
J 0
(-1570 2000);
DISPLAY 0.638298 (-1570 2000);
PAINT MONO (-1570 2000);
DISPLAY INVISIBLE (-1570 2000);
WIRE 16 -1 (-1600 2050)(-2775 2050);
FORCEPROP 2 LAST SIG_NAME PD_CPU1_DMIMODE_OVERRIDE
J 0
(-2600 2060);
DISPLAY 0.617021 (-2600 2060);
PAINT ORANGE (-2600 2060);
WIRE 16 -1 (-1600 1550)(-2775 1550);
FORCEPROP 2 LAST SIG_NAME TP_CPU1_RSVD_208
J 0
(-2600 1560);
DISPLAY 0.617021 (-2600 1560);
PAINT ORANGE (-2600 1560);
FORCEPROP 2 LASTPROP $XRERR UNIQUE?
J 0
(-1570 1550);
DISPLAY 0.638298 (-1570 1550);
PAINT MONO (-1570 1550);
DISPLAY INVISIBLE (-1570 1550);
WIRE 16 -1 (-1600 850)(-2775 850);
FORCEPROP 2 LAST SIG_NAME CLK_100M_CPU1_RC_REFCLK0_DN
J 0
(-2600 860);
DISPLAY 0.617021 (-2600 860);
PAINT ORANGE (-2600 860);
WIRE 16 -1 (-1600 800)(-2775 800);
FORCEPROP 2 LAST SIG_NAME TP_CPU1_RSVD_194
J 0
(-2600 810);
DISPLAY 0.617021 (-2600 810);
PAINT ORANGE (-2600 810);
FORCEPROP 2 LASTPROP $XRERR UNIQUE?
J 0
(-1570 800);
DISPLAY 0.638298 (-1570 800);
PAINT MONO (-1570 800);
DISPLAY INVISIBLE (-1570 800);
WIRE 16 -1 (-1600 1000)(-2775 1000);
FORCEPROP 2 LAST SIG_NAME TP_CPU1_RSVD_198
J 0
(-2600 1010);
DISPLAY 0.617021 (-2600 1010);
PAINT ORANGE (-2600 1010);
FORCEPROP 2 LASTPROP $XRERR UNIQUE?
J 0
(-1570 1000);
DISPLAY 0.638298 (-1570 1000);
PAINT MONO (-1570 1000);
DISPLAY INVISIBLE (-1570 1000);
WIRE 16 -1 (-1600 1450)(-2775 1450);
FORCEPROP 2 LAST SIG_NAME CLK_100M_CPU1_RC_REFCLK0_DP
J 0
(-2600 1460);
DISPLAY 0.617021 (-2600 1460);
PAINT ORANGE (-2600 1460);
WIRE 16 -1 (-1600 1700)(-2775 1700);
FORCEPROP 2 LAST SIG_NAME TP_CPU1_RSVD_210
J 0
(-2600 1710);
DISPLAY 0.617021 (-2600 1710);
PAINT ORANGE (-2600 1710);
FORCEPROP 2 LASTPROP $XRERR UNIQUE?
J 0
(-1570 1700);
DISPLAY 0.638298 (-1570 1700);
PAINT MONO (-1570 1700);
DISPLAY INVISIBLE (-1570 1700);
WIRE 16 -1 (-1600 1850)(-2775 1850);
FORCEPROP 2 LAST SIG_NAME CLK_322M_OSC_CPU1_RC_DN
J 0
(-2610 1860);
DISPLAY 0.617021 (-2610 1860);
PAINT ORANGE (-2610 1860);
WIRE 16 -1 (-1600 3000)(-2775 3000);
FORCEPROP 2 LAST SIG_NAME TP_CPU1_RSVD_TEST_3
J 0
(-2575 3010);
DISPLAY 0.617021 (-2575 3010);
PAINT ORANGE (-2575 3010);
FORCEPROP 2 LASTPROP $XRERR UNIQUE?
J 0
(-1570 3000);
DISPLAY 0.638298 (-1570 3000);
PAINT MONO (-1570 3000);
DISPLAY INVISIBLE (-1570 3000);
WIRE 16 -1 (-2775 3250)(-1600 3250);
FORCEPROP 2 LAST SIG_NAME VSENSE_P1V8MCP_CPU1_SKT_VSEN
J 0
(-2602 3258);
DISPLAY 0.617021 (-2602 3258);
PAINT ORANGE (-2602 3258);
WIRE 16 -1 (-1600 3300)(-2775 3300);
FORCEPROP 2 LAST SIG_NAME TP_CPU1_RSVD_222
J 0
(-2600 3310);
DISPLAY 0.617021 (-2600 3310);
PAINT ORANGE (-2600 3310);
FORCEPROP 2 LASTPROP $XRERR UNIQUE?
J 0
(-1570 3300);
DISPLAY 0.638298 (-1570 3300);
PAINT MONO (-1570 3300);
DISPLAY INVISIBLE (-1570 3300);
WIRE 16 -1 (-1600 3400)(-2775 3400);
FORCEPROP 2 LAST SIG_NAME TP_CPU1_RSVD_224
J 0
(-2600 3410);
DISPLAY 0.617021 (-2600 3410);
PAINT ORANGE (-2600 3410);
FORCEPROP 2 LASTPROP $XRERR UNIQUE?
J 0
(-1570 3400);
DISPLAY 0.638298 (-1570 3400);
PAINT MONO (-1570 3400);
DISPLAY INVISIBLE (-1570 3400);
WIRE 16 -1 (-1600 3450)(-2775 3450);
FORCEPROP 2 LAST SIG_NAME TP_CPU1_RSVD_225
J 0
(-2600 3460);
DISPLAY 0.617021 (-2600 3460);
PAINT ORANGE (-2600 3460);
FORCEPROP 2 LASTPROP $XRERR UNIQUE?
J 0
(-1570 3450);
DISPLAY 0.638298 (-1570 3450);
PAINT MONO (-1570 3450);
DISPLAY INVISIBLE (-1570 3450);
WIRE 16 -1 (-1600 4300)(-2775 4300);
FORCEPROP 2 LAST SIG_NAME TP_CPU1_RSVD_240
J 0
(-2600 4310);
DISPLAY 0.617021 (-2600 4310);
PAINT ORANGE (-2600 4310);
FORCEPROP 2 LASTPROP $XRERR UNIQUE?
J 0
(-1570 4300);
DISPLAY 0.638298 (-1570 4300);
PAINT MONO (-1570 4300);
DISPLAY INVISIBLE (-1570 4300);
WIRE 16 -1 (-1600 4250)(-2775 4250);
FORCEPROP 2 LAST SIG_NAME TP_CPU1_RSVD_239
J 0
(-2600 4260);
DISPLAY 0.617021 (-2600 4260);
PAINT ORANGE (-2600 4260);
FORCEPROP 2 LASTPROP $XRERR UNIQUE?
J 0
(-1570 4250);
DISPLAY 0.638298 (-1570 4250);
PAINT MONO (-1570 4250);
DISPLAY INVISIBLE (-1570 4250);
WIRE 16 -1 (-1600 4200)(-2775 4200);
FORCEPROP 2 LAST SIG_NAME TP_CPU1_RSVD_238
J 0
(-2600 4210);
DISPLAY 0.617021 (-2600 4210);
PAINT ORANGE (-2600 4210);
FORCEPROP 2 LASTPROP $XRERR UNIQUE?
J 0
(-1570 4200);
DISPLAY 0.638298 (-1570 4200);
PAINT MONO (-1570 4200);
DISPLAY INVISIBLE (-1570 4200);
WIRE 16 -1 (-1600 4150)(-2775 4150);
FORCEPROP 2 LAST SIG_NAME TP_CPU1_RSVD_237
J 0
(-2600 4160);
DISPLAY 0.617021 (-2600 4160);
PAINT ORANGE (-2600 4160);
FORCEPROP 2 LASTPROP $XRERR UNIQUE?
J 0
(-1570 4150);
DISPLAY 0.638298 (-1570 4150);
PAINT MONO (-1570 4150);
DISPLAY INVISIBLE (-1570 4150);
WIRE 16 -1 (-1600 3800)(-2775 3800);
FORCEPROP 2 LAST SIG_NAME TP_CPU1_RSVD_231
J 0
(-2600 3810);
DISPLAY 0.617021 (-2600 3810);
PAINT ORANGE (-2600 3810);
FORCEPROP 2 LASTPROP $XRERR UNIQUE?
J 0
(-1570 3800);
DISPLAY 0.638298 (-1570 3800);
PAINT MONO (-1570 3800);
DISPLAY INVISIBLE (-1570 3800);
WIRE 16 -1 (-1600 3850)(-2775 3850);
FORCEPROP 2 LAST SIG_NAME TP_CPU1_RSVD_232
J 0
(-2600 3860);
DISPLAY 0.617021 (-2600 3860);
PAINT ORANGE (-2600 3860);
FORCEPROP 2 LASTPROP $XRERR UNIQUE?
J 0
(-1570 3850);
DISPLAY 0.638298 (-1570 3850);
PAINT MONO (-1570 3850);
DISPLAY INVISIBLE (-1570 3850);
WIRE 16 -1 (-1600 3900)(-2775 3900);
FORCEPROP 2 LAST SIG_NAME TP_CPU1_RSVD_233
J 0
(-2600 3910);
DISPLAY 0.617021 (-2600 3910);
PAINT ORANGE (-2600 3910);
FORCEPROP 2 LASTPROP $XRERR UNIQUE?
J 0
(-1570 3900);
DISPLAY 0.638298 (-1570 3900);
PAINT MONO (-1570 3900);
DISPLAY INVISIBLE (-1570 3900);
WIRE 16 -1 (-1600 1050)(-2775 1050);
FORCEPROP 2 LAST SIG_NAME TP_CPU1_RSVD_199
J 0
(-2600 1060);
DISPLAY 0.617021 (-2600 1060);
PAINT ORANGE (-2600 1060);
FORCEPROP 2 LASTPROP $XRERR UNIQUE?
J 0
(-1570 1050);
DISPLAY 0.638298 (-1570 1050);
PAINT MONO (-1570 1050);
DISPLAY INVISIBLE (-1570 1050);
WIRE 16 -1 (-5275 4350)(-6325 4350);
FORCEPROP 2 LAST SIG_NAME TP_CPU1_RSVD_304
J 0
(-6325 4360);
DISPLAY 0.617021 (-6325 4360);
PAINT ORANGE (-6325 4360);
FORCEPROP 2 LASTPROP $XRERR UNIQUE?
J 0
(-6565 4350);
DISPLAY 0.638298 (-6565 4350);
PAINT MONO (-6565 4350);
DISPLAY INVISIBLE (-6565 4350);
WIRE 16 -1 (-5275 2650)(-6325 2650);
FORCEPROP 2 LAST SIG_NAME TP_CPU1_RSVD_274
J 0
(-6300 2660);
DISPLAY 0.617021 (-6300 2660);
PAINT ORANGE (-6300 2660);
FORCEPROP 2 LASTPROP $XRERR UNIQUE?
J 0
(-6565 2650);
DISPLAY 0.638298 (-6565 2650);
PAINT MONO (-6565 2650);
DISPLAY INVISIBLE (-6565 2650);
WIRE 16 -1 (-5275 2350)(-6325 2350);
FORCEPROP 2 LAST SIG_NAME TP_CPU1_RSVD_268
J 0
(-6300 2360);
DISPLAY 0.617021 (-6300 2360);
PAINT ORANGE (-6300 2360);
FORCEPROP 2 LASTPROP $XRERR UNIQUE?
J 0
(-6565 2350);
DISPLAY 0.638298 (-6565 2350);
PAINT MONO (-6565 2350);
DISPLAY INVISIBLE (-6565 2350);
WIRE 16 -1 (-5275 1350)(-6325 1350);
FORCEPROP 2 LAST SIG_NAME TP_CPU1_RSVD_251
J 0
(-6300 1360);
DISPLAY 0.617021 (-6300 1360);
PAINT ORANGE (-6300 1360);
FORCEPROP 2 LASTPROP $XRERR UNIQUE?
J 0
(-6565 1350);
DISPLAY 0.638298 (-6565 1350);
PAINT MONO (-6565 1350);
DISPLAY INVISIBLE (-6565 1350);
WIRE 16 -1 (-6325 1300)(-5275 1300);
FORCEPROP 2 LAST SIG_NAME TP_CPU1_RSVD_250
J 0
(-6300 1310);
DISPLAY 0.617021 (-6300 1310);
PAINT ORANGE (-6300 1310);
FORCEPROP 2 LASTPROP $XRERR UNIQUE?
J 0
(-6565 1300);
DISPLAY 0.638298 (-6565 1300);
PAINT MONO (-6565 1300);
DISPLAY INVISIBLE (-6565 1300);
WIRE 16 -1 (-5275 1250)(-6325 1250);
FORCEPROP 2 LAST SIG_NAME TP_CPU1_RSVD_249
J 0
(-6300 1260);
DISPLAY 0.617021 (-6300 1260);
PAINT ORANGE (-6300 1260);
FORCEPROP 2 LASTPROP $XRERR UNIQUE?
J 0
(-6565 1250);
DISPLAY 0.638298 (-6565 1250);
PAINT MONO (-6565 1250);
DISPLAY INVISIBLE (-6565 1250);
WIRE 16 -1 (-5275 1150)(-6325 1150);
FORCEPROP 2 LAST SIG_NAME TP_CPU1_RSVD_248
J 0
(-6300 1160);
DISPLAY 0.617021 (-6300 1160);
PAINT ORANGE (-6300 1160);
FORCEPROP 2 LASTPROP $XRERR UNIQUE?
J 0
(-6565 1150);
DISPLAY 0.638298 (-6565 1150);
PAINT MONO (-6565 1150);
DISPLAY INVISIBLE (-6565 1150);
WIRE 16 -1 (-5275 1100)(-6325 1100);
FORCEPROP 2 LAST SIG_NAME TP_CPU1_RSVD_247
J 0
(-6300 1110);
DISPLAY 0.617021 (-6300 1110);
PAINT ORANGE (-6300 1110);
FORCEPROP 2 LASTPROP $XRERR UNIQUE?
J 0
(-6565 1100);
DISPLAY 0.638298 (-6565 1100);
PAINT MONO (-6565 1100);
DISPLAY INVISIBLE (-6565 1100);
WIRE 16 -1 (-5275 1050)(-6325 1050);
FORCEPROP 2 LAST SIG_NAME TP_CPU1_RSVD_246
J 0
(-6300 1060);
DISPLAY 0.617021 (-6300 1060);
PAINT ORANGE (-6300 1060);
FORCEPROP 2 LASTPROP $XRERR UNIQUE?
J 0
(-6565 1050);
DISPLAY 0.638298 (-6565 1050);
PAINT MONO (-6565 1050);
DISPLAY INVISIBLE (-6565 1050);
WIRE 16 -1 (-5275 1000)(-6325 1000);
FORCEPROP 2 LAST SIG_NAME TP_CPU1_RSVD_245
J 0
(-6300 1010);
DISPLAY 0.617021 (-6300 1010);
PAINT ORANGE (-6300 1010);
FORCEPROP 2 LASTPROP $XRERR UNIQUE?
J 0
(-6565 1000);
DISPLAY 0.638298 (-6565 1000);
PAINT MONO (-6565 1000);
DISPLAY INVISIBLE (-6565 1000);
WIRE 16 -1 (-5275 950)(-6325 950);
FORCEPROP 2 LAST SIG_NAME TP_CPU1_RSVD_244
J 0
(-6300 960);
DISPLAY 0.617021 (-6300 960);
PAINT ORANGE (-6300 960);
FORCEPROP 2 LASTPROP $XRERR UNIQUE?
J 0
(-6565 950);
DISPLAY 0.638298 (-6565 950);
PAINT MONO (-6565 950);
DISPLAY INVISIBLE (-6565 950);
WIRE 16 -1 (-6325 3200)(-5275 3200);
FORCEPROP 2 LAST SIG_NAME TP_CPU1_RSVD_282
J 0
(-6300 3210);
DISPLAY 0.617021 (-6300 3210);
PAINT ORANGE (-6300 3210);
FORCEPROP 2 LASTPROP $XRERR UNIQUE?
J 0
(-6565 3200);
DISPLAY 0.638298 (-6565 3200);
PAINT MONO (-6565 3200);
DISPLAY INVISIBLE (-6565 3200);
WIRE 16 -1 (-5275 1400)(-6325 1400);
FORCEPROP 2 LAST SIG_NAME TP_CPU1_RSVD_252
J 0
(-6300 1410);
DISPLAY 0.617021 (-6300 1410);
PAINT ORANGE (-6300 1410);
FORCEPROP 2 LASTPROP $XRERR UNIQUE?
J 0
(-6565 1400);
DISPLAY 0.638298 (-6565 1400);
PAINT MONO (-6565 1400);
DISPLAY INVISIBLE (-6565 1400);
WIRE 16 -1 (-5275 2600)(-6325 2600);
FORCEPROP 2 LAST SIG_NAME TP_CPU1_RSVD_273
J 0
(-6300 2610);
DISPLAY 0.617021 (-6300 2610);
PAINT ORANGE (-6300 2610);
FORCEPROP 2 LASTPROP $XRERR UNIQUE?
J 0
(-6565 2600);
DISPLAY 0.638298 (-6565 2600);
PAINT MONO (-6565 2600);
DISPLAY INVISIBLE (-6565 2600);
WIRE 16 -1 (-5275 2550)(-6325 2550);
FORCEPROP 2 LAST SIG_NAME TP_CPU1_RSVD_272
J 0
(-6300 2560);
DISPLAY 0.617021 (-6300 2560);
PAINT ORANGE (-6300 2560);
FORCEPROP 2 LASTPROP $XRERR UNIQUE?
J 0
(-6565 2550);
DISPLAY 0.638298 (-6565 2550);
PAINT MONO (-6565 2550);
DISPLAY INVISIBLE (-6565 2550);
WIRE 16 -1 (-5275 2500)(-6325 2500);
FORCEPROP 2 LAST SIG_NAME TP_CPU1_RSVD_271
J 0
(-6300 2510);
DISPLAY 0.617021 (-6300 2510);
PAINT ORANGE (-6300 2510);
FORCEPROP 2 LASTPROP $XRERR UNIQUE?
J 0
(-6565 2500);
DISPLAY 0.638298 (-6565 2500);
PAINT MONO (-6565 2500);
DISPLAY INVISIBLE (-6565 2500);
WIRE 16 -1 (-5275 2400)(-6325 2400);
FORCEPROP 2 LAST SIG_NAME TP_CPU1_RSVD_269
J 0
(-6300 2410);
DISPLAY 0.617021 (-6300 2410);
PAINT ORANGE (-6300 2410);
FORCEPROP 2 LASTPROP $XRERR UNIQUE?
J 0
(-6565 2400);
DISPLAY 0.638298 (-6565 2400);
PAINT MONO (-6565 2400);
DISPLAY INVISIBLE (-6565 2400);
WIRE 16 -1 (-5275 750)(-6325 750);
FORCEPROP 2 LAST SIG_NAME TP_CPU1_RSVD_242
J 0
(-6300 760);
DISPLAY 0.617021 (-6300 760);
PAINT ORANGE (-6300 760);
FORCEPROP 2 LASTPROP $XRERR UNIQUE?
J 0
(-6565 750);
DISPLAY 0.638298 (-6565 750);
PAINT MONO (-6565 750);
DISPLAY INVISIBLE (-6565 750);
WIRE 16 -1 (-5275 900)(-6325 900);
FORCEPROP 2 LAST SIG_NAME TP_CPU1_RSVD_243
J 0
(-6300 910);
DISPLAY 0.617021 (-6300 910);
PAINT ORANGE (-6300 910);
FORCEPROP 2 LASTPROP $XRERR UNIQUE?
J 0
(-6565 900);
DISPLAY 0.638298 (-6565 900);
PAINT MONO (-6565 900);
DISPLAY INVISIBLE (-6565 900);
WIRE 16 -1 (-5275 1950)(-6325 1950);
FORCEPROP 2 LAST SIG_NAME TP_CPU1_RSVD_260
J 0
(-6300 1960);
DISPLAY 0.617021 (-6300 1960);
PAINT ORANGE (-6300 1960);
FORCEPROP 2 LASTPROP $XRERR UNIQUE?
J 0
(-6565 1950);
DISPLAY 0.638298 (-6565 1950);
PAINT MONO (-6565 1950);
DISPLAY INVISIBLE (-6565 1950);
WIRE 16 -1 (-5275 2000)(-6325 2000);
FORCEPROP 2 LAST SIG_NAME TP_CPU1_RSVD_261
J 0
(-6300 2010);
DISPLAY 0.617021 (-6300 2010);
PAINT ORANGE (-6300 2010);
FORCEPROP 2 LASTPROP $XRERR UNIQUE?
J 0
(-6565 2000);
DISPLAY 0.638298 (-6565 2000);
PAINT MONO (-6565 2000);
DISPLAY INVISIBLE (-6565 2000);
WIRE 16 -1 (-5275 2050)(-6325 2050);
FORCEPROP 2 LAST SIG_NAME TP_CPU1_RSVD_262
J 0
(-6300 2060);
DISPLAY 0.617021 (-6300 2060);
PAINT ORANGE (-6300 2060);
FORCEPROP 2 LASTPROP $XRERR UNIQUE?
J 0
(-6565 2050);
DISPLAY 0.638298 (-6565 2050);
PAINT MONO (-6565 2050);
DISPLAY INVISIBLE (-6565 2050);
WIRE 16 -1 (-5275 2250)(-6325 2250);
FORCEPROP 2 LAST SIG_NAME TP_CPU1_RSVD_266
J 0
(-6300 2260);
DISPLAY 0.617021 (-6300 2260);
PAINT ORANGE (-6300 2260);
FORCEPROP 2 LASTPROP $XRERR UNIQUE?
J 0
(-6565 2250);
DISPLAY 0.638298 (-6565 2250);
PAINT MONO (-6565 2250);
DISPLAY INVISIBLE (-6565 2250);
WIRE 16 -1 (-5275 2300)(-6325 2300);
FORCEPROP 2 LAST SIG_NAME TP_CPU1_RSVD_267
J 0
(-6300 2310);
DISPLAY 0.617021 (-6300 2310);
PAINT ORANGE (-6300 2310);
FORCEPROP 2 LASTPROP $XRERR UNIQUE?
J 0
(-6565 2300);
DISPLAY 0.638298 (-6565 2300);
PAINT MONO (-6565 2300);
DISPLAY INVISIBLE (-6565 2300);
WIRE 16 -1 (-5275 2450)(-6325 2450);
FORCEPROP 2 LAST SIG_NAME TP_CPU1_RSVD_270
J 0
(-6300 2460);
DISPLAY 0.617021 (-6300 2460);
PAINT ORANGE (-6300 2460);
FORCEPROP 2 LASTPROP $XRERR UNIQUE?
J 0
(-6565 2450);
DISPLAY 0.638298 (-6565 2450);
PAINT MONO (-6565 2450);
DISPLAY INVISIBLE (-6565 2450);
WIRE 16 -1 (-5275 3300)(-6325 3300);
FORCEPROP 2 LAST SIG_NAME TP_CPU1_RSVD_284
J 0
(-6300 3310);
DISPLAY 0.617021 (-6300 3310);
PAINT ORANGE (-6300 3310);
FORCEPROP 2 LASTPROP $XRERR UNIQUE?
J 0
(-6565 3300);
DISPLAY 0.638298 (-6565 3300);
PAINT MONO (-6565 3300);
DISPLAY INVISIBLE (-6565 3300);
WIRE 16 -1 (-5275 3550)(-6325 3550);
FORCEPROP 2 LAST SIG_NAME TP_CPU1_RSVD_289
J 0
(-6300 3560);
DISPLAY 0.617021 (-6300 3560);
PAINT ORANGE (-6300 3560);
FORCEPROP 2 LASTPROP $XRERR UNIQUE?
J 0
(-6565 3550);
DISPLAY 0.638298 (-6565 3550);
PAINT MONO (-6565 3550);
DISPLAY INVISIBLE (-6565 3550);
WIRE 16 -1 (-5275 3700)(-6325 3700);
FORCEPROP 2 LAST SIG_NAME TP_CPU1_RSVD_291
J 0
(-6300 3710);
DISPLAY 0.617021 (-6300 3710);
PAINT ORANGE (-6300 3710);
FORCEPROP 2 LASTPROP $XRERR UNIQUE?
J 0
(-6565 3700);
DISPLAY 0.638298 (-6565 3700);
PAINT MONO (-6565 3700);
DISPLAY INVISIBLE (-6565 3700);
WIRE 16 -1 (-5275 3800)(-6325 3800);
FORCEPROP 2 LAST SIG_NAME TP_CPU1_RSVD_293
J 0
(-6300 3810);
DISPLAY 0.617021 (-6300 3810);
PAINT ORANGE (-6300 3810);
FORCEPROP 2 LASTPROP $XRERR UNIQUE?
J 0
(-6565 3800);
DISPLAY 0.638298 (-6565 3800);
PAINT MONO (-6565 3800);
DISPLAY INVISIBLE (-6565 3800);
WIRE 16 -1 (-5275 3750)(-6325 3750);
FORCEPROP 2 LAST SIG_NAME TP_CPU1_RSVD_292
J 0
(-6300 3760);
DISPLAY 0.617021 (-6300 3760);
PAINT ORANGE (-6300 3760);
FORCEPROP 2 LASTPROP $XRERR UNIQUE?
J 0
(-6565 3750);
DISPLAY 0.638298 (-6565 3750);
PAINT MONO (-6565 3750);
DISPLAY INVISIBLE (-6565 3750);
WIRE 16 -1 (-6325 1450)(-5275 1450);
FORCEPROP 2 LAST SIG_NAME TP_CPU1_RSVD_253
J 0
(-6300 1460);
DISPLAY 0.617021 (-6300 1460);
PAINT ORANGE (-6300 1460);
FORCEPROP 2 LASTPROP $XRERR UNIQUE?
J 0
(-6565 1450);
DISPLAY 0.638298 (-6565 1450);
PAINT MONO (-6565 1450);
DISPLAY INVISIBLE (-6565 1450);
WIRE 16 -1 (-5275 1600)(-6325 1600);
FORCEPROP 2 LAST SIG_NAME TP_CPU1_RSVD_TEST_11
J 0
(-6300 1610);
DISPLAY 0.617021 (-6300 1610);
PAINT ORANGE (-6300 1610);
FORCEPROP 2 LASTPROP $XRERR UNIQUE?
J 0
(-6565 1600);
DISPLAY 0.638298 (-6565 1600);
PAINT MONO (-6565 1600);
DISPLAY INVISIBLE (-6565 1600);
WIRE 16 -1 (-6325 1850)(-5275 1850);
FORCEPROP 2 LAST SIG_NAME TP_CPU1_RSVD_259
J 0
(-6300 1860);
DISPLAY 0.617021 (-6300 1860);
PAINT ORANGE (-6300 1860);
FORCEPROP 2 LASTPROP $XRERR UNIQUE?
J 0
(-6565 1850);
DISPLAY 0.638298 (-6565 1850);
PAINT MONO (-6565 1850);
DISPLAY INVISIBLE (-6565 1850);
WIRE 16 -1 (-6325 1800)(-5275 1800);
FORCEPROP 2 LAST SIG_NAME TP_CPU1_RSVD_258
J 0
(-6300 1810);
DISPLAY 0.617021 (-6300 1810);
PAINT ORANGE (-6300 1810);
FORCEPROP 2 LASTPROP $XRERR UNIQUE?
J 0
(-6565 1800);
DISPLAY 0.638298 (-6565 1800);
PAINT MONO (-6565 1800);
DISPLAY INVISIBLE (-6565 1800);
WIRE 16 -1 (-6325 1700)(-5275 1700);
FORCEPROP 2 LAST SIG_NAME TP_CPU1_RSVD_256
J 0
(-6300 1710);
DISPLAY 0.617021 (-6300 1710);
PAINT ORANGE (-6300 1710);
FORCEPROP 2 LASTPROP $XRERR UNIQUE?
J 0
(-6565 1700);
DISPLAY 0.638298 (-6565 1700);
PAINT MONO (-6565 1700);
DISPLAY INVISIBLE (-6565 1700);
WIRE 16 -1 (-5275 2200)(-6325 2200);
FORCEPROP 2 LAST SIG_NAME TP_CPU1_RSVD_265
J 0
(-6300 2210);
DISPLAY 0.617021 (-6300 2210);
PAINT ORANGE (-6300 2210);
FORCEPROP 2 LASTPROP $XRERR UNIQUE?
J 0
(-6565 2200);
DISPLAY 0.638298 (-6565 2200);
PAINT MONO (-6565 2200);
DISPLAY INVISIBLE (-6565 2200);
WIRE 16 -1 (-5275 3100)(-6325 3100);
FORCEPROP 2 LAST SIG_NAME TP_CPU1_RSVD_281
J 0
(-6300 3110);
DISPLAY 0.617021 (-6300 3110);
PAINT ORANGE (-6300 3110);
FORCEPROP 2 LASTPROP $XRERR UNIQUE?
J 0
(-6565 3100);
DISPLAY 0.638298 (-6565 3100);
PAINT MONO (-6565 3100);
DISPLAY INVISIBLE (-6565 3100);
WIRE 16 -1 (-5275 3050)(-6325 3050);
FORCEPROP 2 LAST SIG_NAME TP_CPU1_RSVD_280
J 0
(-6300 3060);
DISPLAY 0.617021 (-6300 3060);
PAINT ORANGE (-6300 3060);
FORCEPROP 2 LASTPROP $XRERR UNIQUE?
J 0
(-6565 3050);
DISPLAY 0.638298 (-6565 3050);
PAINT MONO (-6565 3050);
DISPLAY INVISIBLE (-6565 3050);
WIRE 16 -1 (-5275 3000)(-6325 3000);
FORCEPROP 2 LAST SIG_NAME TP_CPU1_RSVD_279
J 0
(-6300 3010);
DISPLAY 0.617021 (-6300 3010);
PAINT ORANGE (-6300 3010);
FORCEPROP 2 LASTPROP $XRERR UNIQUE?
J 0
(-6565 3000);
DISPLAY 0.638298 (-6565 3000);
PAINT MONO (-6565 3000);
DISPLAY INVISIBLE (-6565 3000);
WIRE 16 -1 (-5275 2950)(-6325 2950);
FORCEPROP 2 LAST SIG_NAME TP_CPU1_RSVD_278
J 0
(-6300 2960);
DISPLAY 0.617021 (-6300 2960);
PAINT ORANGE (-6300 2960);
FORCEPROP 2 LASTPROP $XRERR UNIQUE?
J 0
(-6565 2950);
DISPLAY 0.638298 (-6565 2950);
PAINT MONO (-6565 2950);
DISPLAY INVISIBLE (-6565 2950);
WIRE 16 -1 (-5275 2800)(-6325 2800);
FORCEPROP 2 LAST SIG_NAME TP_CPU1_RSVD_276
J 0
(-6300 2810);
DISPLAY 0.617021 (-6300 2810);
PAINT ORANGE (-6300 2810);
FORCEPROP 2 LASTPROP $XRERR UNIQUE?
J 0
(-6565 2800);
DISPLAY 0.638298 (-6565 2800);
PAINT MONO (-6565 2800);
DISPLAY INVISIBLE (-6565 2800);
WIRE 16 -1 (-5275 2700)(-6325 2700);
FORCEPROP 2 LAST SIG_NAME TP_CPU1_RSVD_275
J 0
(-6300 2710);
DISPLAY 0.617021 (-6300 2710);
PAINT ORANGE (-6300 2710);
FORCEPROP 2 LASTPROP $XRERR UNIQUE?
J 0
(-6565 2700);
DISPLAY 0.638298 (-6565 2700);
PAINT MONO (-6565 2700);
DISPLAY INVISIBLE (-6565 2700);
WIRE 16 -1 (-7050 1750)(-5275 1750);
FORCEPROP 2 LAST SIG_NAME FM_CPU1_RC_ERROR_N
J 0
(-7025 1760);
DISPLAY 0.617021 (-7025 1760);
PAINT ORANGE (-7025 1760);
WIRE 16 -1 (-5275 4300)(-6325 4300);
FORCEPROP 2 LAST SIG_NAME TP_CPU1_RSVD_303
J 0
(-6325 4310);
DISPLAY 0.617021 (-6325 4310);
PAINT ORANGE (-6325 4310);
FORCEPROP 2 LASTPROP $XRERR UNIQUE?
J 0
(-6565 4300);
DISPLAY 0.638298 (-6565 4300);
PAINT MONO (-6565 4300);
DISPLAY INVISIBLE (-6565 4300);
WIRE 16 -1 (-5275 4100)(-6325 4100);
FORCEPROP 2 LAST SIG_NAME TP_CPU1_RSVD_299
J 0
(-6300 4110);
DISPLAY 0.617021 (-6300 4110);
PAINT ORANGE (-6300 4110);
FORCEPROP 2 LASTPROP $XRERR UNIQUE?
J 0
(-6565 4100);
DISPLAY 0.638298 (-6565 4100);
PAINT MONO (-6565 4100);
DISPLAY INVISIBLE (-6565 4100);
WIRE 16 -1 (-5275 4150)(-6325 4150);
FORCEPROP 2 LAST SIG_NAME TP_CPU1_RSVD_300
J 0
(-6300 4160);
DISPLAY 0.617021 (-6300 4160);
PAINT ORANGE (-6300 4160);
FORCEPROP 2 LASTPROP $XRERR UNIQUE?
J 0
(-6565 4150);
DISPLAY 0.638298 (-6565 4150);
PAINT MONO (-6565 4150);
DISPLAY INVISIBLE (-6565 4150);
WIRE 16 -1 (-1600 1800)(-2775 1800);
FORCEPROP 2 LAST SIG_NAME TP_CPU1_RSVD_212
J 0
(-2600 1810);
DISPLAY 0.617021 (-2600 1810);
PAINT ORANGE (-2600 1810);
FORCEPROP 2 LASTPROP $XRERR UNIQUE?
J 0
(-1570 1800);
DISPLAY 0.638298 (-1570 1800);
PAINT MONO (-1570 1800);
DISPLAY INVISIBLE (-1570 1800);
WIRE 16 -1 (-1600 3500)(-2775 3500);
FORCEPROP 2 LAST SIG_NAME TP_CPU1_RSVD_226
J 0
(-2600 3510);
DISPLAY 0.617021 (-2600 3510);
PAINT ORANGE (-2600 3510);
FORCEPROP 2 LASTPROP $XRERR UNIQUE?
J 0
(-1570 3500);
DISPLAY 0.638298 (-1570 3500);
PAINT MONO (-1570 3500);
DISPLAY INVISIBLE (-1570 3500);
WIRE 16 -1 (-1600 3550)(-2775 3550);
FORCEPROP 2 LAST SIG_NAME TP_CPU1_RSVD_227
J 0
(-2600 3560);
DISPLAY 0.617021 (-2600 3560);
PAINT ORANGE (-2600 3560);
FORCEPROP 2 LASTPROP $XRERR UNIQUE?
J 0
(-1570 3550);
DISPLAY 0.638298 (-1570 3550);
PAINT MONO (-1570 3550);
DISPLAY INVISIBLE (-1570 3550);
WIRE 16 -1 (-1600 3700)(-2775 3700);
FORCEPROP 2 LAST SIG_NAME TP_CPU1_RSVD_229
J 0
(-2600 3710);
DISPLAY 0.617021 (-2600 3710);
PAINT ORANGE (-2600 3710);
FORCEPROP 2 LASTPROP $XRERR UNIQUE?
J 0
(-1570 3700);
DISPLAY 0.638298 (-1570 3700);
PAINT MONO (-1570 3700);
DISPLAY INVISIBLE (-1570 3700);
WIRE 16 -1 (-1600 3750)(-2775 3750);
FORCEPROP 2 LAST SIG_NAME TP_CPU1_RSVD_230
J 0
(-2600 3760);
DISPLAY 0.617021 (-2600 3760);
PAINT ORANGE (-2600 3760);
FORCEPROP 2 LASTPROP $XRERR UNIQUE?
J 0
(-1570 3750);
DISPLAY 0.638298 (-1570 3750);
PAINT MONO (-1570 3750);
DISPLAY INVISIBLE (-1570 3750);
WIRE 16 -1 (-1600 3950)(-2775 3950);
FORCEPROP 2 LAST SIG_NAME TP_CPU1_RSVD_234
J 0
(-2600 3960);
DISPLAY 0.617021 (-2600 3960);
PAINT ORANGE (-2600 3960);
FORCEPROP 2 LASTPROP $XRERR UNIQUE?
J 0
(-1570 3950);
DISPLAY 0.638298 (-1570 3950);
PAINT MONO (-1570 3950);
DISPLAY INVISIBLE (-1570 3950);
WIRE 16 -1 (-1600 4050)(-2775 4050);
FORCEPROP 2 LAST SIG_NAME TP_CPU1_RSVD_235
J 0
(-2600 4060);
DISPLAY 0.617021 (-2600 4060);
PAINT ORANGE (-2600 4060);
FORCEPROP 2 LASTPROP $XRERR UNIQUE?
J 0
(-1570 4050);
DISPLAY 0.638298 (-1570 4050);
PAINT MONO (-1570 4050);
DISPLAY INVISIBLE (-1570 4050);
WIRE 16 -1 (-1600 4100)(-2775 4100);
FORCEPROP 2 LAST SIG_NAME TP_CPU1_RSVD_236
J 0
(-2600 4110);
DISPLAY 0.617021 (-2600 4110);
PAINT ORANGE (-2600 4110);
FORCEPROP 2 LASTPROP $XRERR UNIQUE?
J 0
(-1570 4100);
DISPLAY 0.638298 (-1570 4100);
PAINT MONO (-1570 4100);
DISPLAY INVISIBLE (-1570 4100);
WIRE 16 -1 (-1600 4350)(-2775 4350);
FORCEPROP 2 LAST SIG_NAME TP_CPU1_RSVD_241
J 0
(-2600 4360);
DISPLAY 0.617021 (-2600 4360);
PAINT ORANGE (-2600 4360);
FORCEPROP 2 LASTPROP $XRERR UNIQUE?
J 0
(-1570 4350);
DISPLAY 0.638298 (-1570 4350);
PAINT MONO (-1570 4350);
DISPLAY INVISIBLE (-1570 4350);
DOT 1 (-950 1650);
DOT 1 (-375 2525);
DOT 1 (-2600 900);
DOT 1 (-2600 1150);
DOT 1 (-2600 1100);
DOT 1 (-2600 1200);
DOT 1 (-950 1100);
DOT 1 (-950 1500);
DOT 1 (-5450 3900);
DOT 1 (-5450 3950);
DOT 1 (-5450 4250);
DOT 1 (-7250 4250);
FORCENOTE
TP FAB3 RECONNECT 0921
(-2600 2425) 0;
DISPLAY LEFT (-2600 2425);
DISPLAY 0.638298 (-2600 2425);
PAINT RED (-2600 2425);
FORCENOTE
BOM_COST=PROC_SOCKET
(-7925 225) 0;
DISPLAY LEFT (-7925 225);
DISPLAY 1.723404 (-7925 225);
PAINT PURPLE (-7925 225);
FORCENOTE
ROOM=CPU1
(-7925 350) 0;
DISPLAY LEFT (-7925 350);
DISPLAY 1.723404 (-7925 350);
PAINT PURPLE (-7925 350);
QUIT
